FILE_TYPE = MACRO_DRAWING;
SET COLOR_WIRE YELLOW;
SET COLOR_PROP ORANGE;
SET COLOR_DOT WHITE;
SET COLOR_ARC YELLOW;
SET COLOR_BODY GREEN;
SET COLOR_NOTE PURPLE;
SET PROP_DISPLAY VALUE;
SET PAGE_NUMBER P37;
FORCEADD GENOA_SP5..1
(-4575 3675);
FORCEPROP 1 LAST LOCATION U26
J 0
(-5220 6481);
DISPLAY 0.489362 (-5220 6481);
PAINT SKYBLUE (-5220 6481);
FORCEPROP 0 LAST $SEC 1
J 0
(-5200 6525);
DISPLAY 0.680851 (-5200 6525);
PAINT MONO (-5200 6525);
DISPLAY INVISIBLE (-5200 6525);
FORCEPROP 0 LAST CDS_SEC 1
J 0
(-5225 6425);
DISPLAY 1.021277 (-5225 6425);
DISPLAY INVISIBLE (-5225 6425);
FORCEPROP 0 LASTPIN (-5375 3075) $PN BC74
J 2
(-5385 3085);
DISPLAY 0.489362 (-5385 3085);
PAINT MONO (-5385 3085);
FORCEPROP 0 LASTPIN (-5375 3025) $PN BD74
J 2
(-5385 3035);
DISPLAY 0.489362 (-5385 3035);
PAINT MONO (-5385 3035);
FORCEPROP 0 LASTPIN (-5375 1925) $PN BF74
J 2
(-5385 1935);
DISPLAY 0.489362 (-5385 1935);
PAINT MONO (-5385 1935);
FORCEPROP 0 LASTPIN (-5375 1875) $PN BG74
J 2
(-5385 1885);
DISPLAY 0.489362 (-5385 1885);
PAINT MONO (-5385 1885);
FORCEPROP 0 LASTPIN (-5375 2225) $PN AR74
J 2
(-5385 2235);
DISPLAY 0.489362 (-5385 2235);
PAINT MONO (-5385 2235);
FORCEPROP 0 LASTPIN (-5375 2125) $PN AT74
J 2
(-5385 2135);
DISPLAY 0.489362 (-5385 2135);
PAINT MONO (-5385 2135);
FORCEPROP 0 LASTPIN (-5375 2925) $PN AV74
J 2
(-5385 2935);
DISPLAY 0.489362 (-5385 2935);
PAINT MONO (-5385 2935);
FORCEPROP 0 LASTPIN (-5375 2875) $PN AW73
J 2
(-5385 2885);
DISPLAY 0.489362 (-5385 2885);
PAINT MONO (-5385 2885);
FORCEPROP 0 LASTPIN (-5375 2775) $PN BN73
J 2
(-5385 2785);
DISPLAY 0.489362 (-5385 2785);
PAINT MONO (-5385 2785);
FORCEPROP 0 LASTPIN (-5375 1775) $PN AU74
J 2
(-5385 1785);
DISPLAY 0.489362 (-5385 1785);
PAINT MONO (-5385 1785);
FORCEPROP 0 LASTPIN (-5375 1725) $PN AV72
J 2
(-5385 1735);
DISPLAY 0.489362 (-5385 1735);
PAINT MONO (-5385 1735);
FORCEPROP 0 LASTPIN (-5375 1625) $PN BP72
J 2
(-5385 1635);
DISPLAY 0.489362 (-5385 1635);
PAINT MONO (-5385 1635);
FORCEPROP 0 LASTPIN (-5375 3925) $PN AW74
J 2
(-5385 3935);
DISPLAY 0.489362 (-5385 3935);
PAINT MONO (-5385 3935);
FORCEPROP 0 LASTPIN (-5375 3875) $PN AY74
J 2
(-5385 3885);
DISPLAY 0.489362 (-5385 3885);
PAINT MONO (-5385 3885);
FORCEPROP 0 LASTPIN (-5375 3825) $PN AY72
J 2
(-5385 3835);
DISPLAY 0.489362 (-5385 3835);
PAINT MONO (-5385 3835);
FORCEPROP 0 LASTPIN (-5375 3775) $PN BA73
J 2
(-5385 3785);
DISPLAY 0.489362 (-5385 3785);
PAINT MONO (-5385 3785);
FORCEPROP 0 LASTPIN (-5375 3725) $PN BA74
J 2
(-5385 3735);
DISPLAY 0.489362 (-5385 3735);
PAINT MONO (-5385 3735);
FORCEPROP 0 LASTPIN (-5375 3675) $PN BB74
J 2
(-5385 3685);
DISPLAY 0.489362 (-5385 3685);
PAINT MONO (-5385 3685);
FORCEPROP 0 LASTPIN (-5375 3625) $PN BB72
J 2
(-5385 3635);
DISPLAY 0.489362 (-5385 3635);
PAINT MONO (-5385 3635);
FORCEPROP 0 LASTPIN (-3775 2475) $PN AJ74
J 0
(-3765 2485);
DISPLAY 0.489362 (-3765 2485);
PAINT MONO (-3765 2485);
FORCEPROP 0 LASTPIN (-3775 2425) $PN AK72
J 0
(-3765 2435);
DISPLAY 0.489362 (-3765 2435);
PAINT MONO (-3765 2435);
FORCEPROP 0 LASTPIN (-3775 2375) $PN AK74
J 0
(-3765 2385);
DISPLAY 0.489362 (-3765 2385);
PAINT MONO (-3765 2385);
FORCEPROP 0 LASTPIN (-3775 2325) $PN AL73
J 0
(-3765 2335);
DISPLAY 0.489362 (-3765 2335);
PAINT MONO (-3765 2335);
FORCEPROP 0 LASTPIN (-3775 2275) $PN AN74
J 0
(-3765 2285);
DISPLAY 0.489362 (-3765 2285);
PAINT MONO (-3765 2285);
FORCEPROP 0 LASTPIN (-3775 2225) $PN AP72
J 0
(-3765 2235);
DISPLAY 0.489362 (-3765 2235);
PAINT MONO (-3765 2235);
FORCEPROP 0 LASTPIN (-3775 2175) $PN AP74
J 0
(-3765 2185);
DISPLAY 0.489362 (-3765 2185);
PAINT MONO (-3765 2185);
FORCEPROP 0 LASTPIN (-3775 2125) $PN AR73
J 0
(-3765 2135);
DISPLAY 0.489362 (-3765 2135);
PAINT MONO (-3765 2135);
FORCEPROP 0 LASTPIN (-3775 6075) $PN E74
J 0
(-3765 6085);
DISPLAY 0.489362 (-3765 6085);
PAINT MONO (-3765 6085);
FORCEPROP 0 LASTPIN (-3775 6025) $PN F72
J 0
(-3765 6035);
DISPLAY 0.489362 (-3765 6035);
PAINT MONO (-3765 6035);
FORCEPROP 0 LASTPIN (-3775 5975) $PN F74
J 0
(-3765 5985);
DISPLAY 0.489362 (-3765 5985);
PAINT MONO (-3765 5985);
FORCEPROP 0 LASTPIN (-3775 5925) $PN G73
J 0
(-3765 5935);
DISPLAY 0.489362 (-3765 5935);
PAINT MONO (-3765 5935);
FORCEPROP 0 LASTPIN (-3775 5875) $PN J74
J 0
(-3765 5885);
DISPLAY 0.489362 (-3765 5885);
PAINT MONO (-3765 5885);
FORCEPROP 0 LASTPIN (-3775 5825) $PN K72
J 0
(-3765 5835);
DISPLAY 0.489362 (-3765 5835);
PAINT MONO (-3765 5835);
FORCEPROP 0 LASTPIN (-3775 5775) $PN K74
J 0
(-3765 5785);
DISPLAY 0.489362 (-3765 5785);
PAINT MONO (-3765 5785);
FORCEPROP 0 LASTPIN (-3775 5725) $PN L73
J 0
(-3765 5735);
DISPLAY 0.489362 (-3765 5735);
PAINT MONO (-3765 5735);
FORCEPROP 0 LASTPIN (-3775 5625) $PN L74
J 0
(-3765 5635);
DISPLAY 0.489362 (-3765 5635);
PAINT MONO (-3765 5635);
FORCEPROP 0 LASTPIN (-3775 5575) $PN M72
J 0
(-3765 5585);
DISPLAY 0.489362 (-3765 5585);
PAINT MONO (-3765 5585);
FORCEPROP 0 LASTPIN (-3775 5525) $PN M74
J 0
(-3765 5535);
DISPLAY 0.489362 (-3765 5535);
PAINT MONO (-3765 5535);
FORCEPROP 0 LASTPIN (-3775 5475) $PN N73
J 0
(-3765 5485);
DISPLAY 0.489362 (-3765 5485);
PAINT MONO (-3765 5485);
FORCEPROP 0 LASTPIN (-3775 5425) $PN R74
J 0
(-3765 5435);
DISPLAY 0.489362 (-3765 5435);
PAINT MONO (-3765 5435);
FORCEPROP 0 LASTPIN (-3775 5375) $PN T72
J 0
(-3765 5385);
DISPLAY 0.489362 (-3765 5385);
PAINT MONO (-3765 5385);
FORCEPROP 0 LASTPIN (-3775 5325) $PN T74
J 0
(-3765 5335);
DISPLAY 0.489362 (-3765 5335);
PAINT MONO (-3765 5335);
FORCEPROP 0 LASTPIN (-3775 5275) $PN U73
J 0
(-3765 5285);
DISPLAY 0.489362 (-3765 5285);
PAINT MONO (-3765 5285);
FORCEPROP 0 LASTPIN (-3775 5175) $PN U74
J 0
(-3765 5185);
DISPLAY 0.489362 (-3765 5185);
PAINT MONO (-3765 5185);
FORCEPROP 0 LASTPIN (-3775 5125) $PN V72
J 0
(-3765 5135);
DISPLAY 0.489362 (-3765 5135);
PAINT MONO (-3765 5135);
FORCEPROP 0 LASTPIN (-3775 5075) $PN V74
J 0
(-3765 5085);
DISPLAY 0.489362 (-3765 5085);
PAINT MONO (-3765 5085);
FORCEPROP 0 LASTPIN (-3775 5025) $PN W73
J 0
(-3765 5035);
DISPLAY 0.489362 (-3765 5035);
PAINT MONO (-3765 5035);
FORCEPROP 0 LASTPIN (-3775 4975) $PN AA74
J 0
(-3765 4985);
DISPLAY 0.489362 (-3765 4985);
PAINT MONO (-3765 4985);
FORCEPROP 0 LASTPIN (-3775 4925) $PN AB72
J 0
(-3765 4935);
DISPLAY 0.489362 (-3765 4935);
PAINT MONO (-3765 4935);
FORCEPROP 0 LASTPIN (-3775 4875) $PN AB74
J 0
(-3765 4885);
DISPLAY 0.489362 (-3765 4885);
PAINT MONO (-3765 4885);
FORCEPROP 0 LASTPIN (-3775 4825) $PN AC73
J 0
(-3765 4835);
DISPLAY 0.489362 (-3765 4835);
PAINT MONO (-3765 4835);
FORCEPROP 0 LASTPIN (-3775 4725) $PN AC74
J 0
(-3765 4735);
DISPLAY 0.489362 (-3765 4735);
PAINT MONO (-3765 4735);
FORCEPROP 0 LASTPIN (-3775 4675) $PN AD72
J 0
(-3765 4685);
DISPLAY 0.489362 (-3765 4685);
PAINT MONO (-3765 4685);
FORCEPROP 0 LASTPIN (-3775 4625) $PN AD74
J 0
(-3765 4635);
DISPLAY 0.489362 (-3765 4635);
PAINT MONO (-3765 4635);
FORCEPROP 0 LASTPIN (-3775 4575) $PN AE73
J 0
(-3765 4585);
DISPLAY 0.489362 (-3765 4585);
PAINT MONO (-3765 4585);
FORCEPROP 0 LASTPIN (-3775 4525) $PN AG74
J 0
(-3765 4535);
DISPLAY 0.489362 (-3765 4535);
PAINT MONO (-3765 4535);
FORCEPROP 0 LASTPIN (-3775 4475) $PN AH72
J 0
(-3765 4485);
DISPLAY 0.489362 (-3765 4485);
PAINT MONO (-3765 4485);
FORCEPROP 0 LASTPIN (-3775 4425) $PN AH74
J 0
(-3765 4435);
DISPLAY 0.489362 (-3765 4435);
PAINT MONO (-3765 4435);
FORCEPROP 0 LASTPIN (-3775 4375) $PN AJ73
J 0
(-3765 4385);
DISPLAY 0.489362 (-3765 4385);
PAINT MONO (-3765 4385);
FORCEPROP 0 LASTPIN (-5375 6075) $PN G74
J 2
(-5385 6085);
DISPLAY 0.489362 (-5385 6085);
PAINT MONO (-5385 6085);
FORCEPROP 0 LASTPIN (-5375 5975) $PN N74
J 2
(-5385 5985);
DISPLAY 0.489362 (-5385 5985);
PAINT MONO (-5385 5985);
FORCEPROP 0 LASTPIN (-5375 5875) $PN W74
J 2
(-5385 5885);
DISPLAY 0.489362 (-5385 5885);
PAINT MONO (-5385 5885);
FORCEPROP 0 LASTPIN (-5375 5775) $PN AE74
J 2
(-5385 5785);
DISPLAY 0.489362 (-5385 5785);
PAINT MONO (-5385 5785);
FORCEPROP 0 LASTPIN (-5375 5675) $PN AL74
J 2
(-5385 5685);
DISPLAY 0.489362 (-5385 5685);
PAINT MONO (-5385 5685);
FORCEPROP 0 LASTPIN (-5375 5575) $PN J73
J 2
(-5385 5585);
DISPLAY 0.489362 (-5385 5585);
PAINT MONO (-5385 5585);
FORCEPROP 0 LASTPIN (-5375 5475) $PN R73
J 2
(-5385 5485);
DISPLAY 0.489362 (-5385 5485);
PAINT MONO (-5385 5485);
FORCEPROP 0 LASTPIN (-5375 5375) $PN AA73
J 2
(-5385 5385);
DISPLAY 0.489362 (-5385 5385);
PAINT MONO (-5385 5385);
FORCEPROP 0 LASTPIN (-5375 5275) $PN AG73
J 2
(-5385 5285);
DISPLAY 0.489362 (-5385 5285);
PAINT MONO (-5385 5285);
FORCEPROP 0 LASTPIN (-5375 5175) $PN AN73
J 2
(-5385 5185);
DISPLAY 0.489362 (-5385 5185);
PAINT MONO (-5385 5185);
FORCEPROP 0 LASTPIN (-5375 6025) $PN H74
J 2
(-5385 6035);
DISPLAY 0.489362 (-5385 6035);
PAINT MONO (-5385 6035);
FORCEPROP 0 LASTPIN (-5375 5925) $PN P74
J 2
(-5385 5935);
DISPLAY 0.489362 (-5385 5935);
PAINT MONO (-5385 5935);
FORCEPROP 0 LASTPIN (-5375 5825) $PN Y74
J 2
(-5385 5835);
DISPLAY 0.489362 (-5385 5835);
PAINT MONO (-5385 5835);
FORCEPROP 0 LASTPIN (-5375 5725) $PN AF74
J 2
(-5385 5735);
DISPLAY 0.489362 (-5385 5735);
PAINT MONO (-5385 5735);
FORCEPROP 0 LASTPIN (-5375 5625) $PN AM74
J 2
(-5385 5635);
DISPLAY 0.489362 (-5385 5635);
PAINT MONO (-5385 5635);
FORCEPROP 0 LASTPIN (-5375 5525) $PN H72
J 2
(-5385 5535);
DISPLAY 0.489362 (-5385 5535);
PAINT MONO (-5385 5535);
FORCEPROP 0 LASTPIN (-5375 5425) $PN P72
J 2
(-5385 5435);
DISPLAY 0.489362 (-5385 5435);
PAINT MONO (-5385 5435);
FORCEPROP 0 LASTPIN (-5375 5325) $PN Y72
J 2
(-5385 5335);
DISPLAY 0.489362 (-5385 5335);
PAINT MONO (-5385 5335);
FORCEPROP 0 LASTPIN (-5375 5225) $PN AF72
J 2
(-5385 5235);
DISPLAY 0.489362 (-5385 5235);
PAINT MONO (-5385 5235);
FORCEPROP 0 LASTPIN (-5375 5125) $PN AM72
J 2
(-5385 5135);
DISPLAY 0.489362 (-5385 5135);
PAINT MONO (-5385 5135);
FORCEPROP 0 LASTPIN (-5375 2675) $PN BC73
J 2
(-5385 2685);
DISPLAY 0.489362 (-5385 2685);
PAINT MONO (-5385 2685);
FORCEPROP 0 LASTPIN (-5375 2575) $PN BM72
J 2
(-5385 2585);
DISPLAY 0.489362 (-5385 2585);
PAINT MONO (-5385 2585);
FORCEPROP 0 LASTPIN (-5375 2525) $PN BN74
J 2
(-5385 2535);
DISPLAY 0.489362 (-5385 2535);
PAINT MONO (-5385 2535);
FORCEPROP 0 LASTPIN (-5375 2425) $PN BP74
J 2
(-5385 2435);
DISPLAY 0.489362 (-5385 2435);
PAINT MONO (-5385 2435);
FORCEPROP 0 LASTPIN (-5375 1525) $PN BL73
J 2
(-5385 1535);
DISPLAY 0.489362 (-5385 1535);
PAINT MONO (-5385 1535);
FORCEPROP 0 LASTPIN (-5375 1475) $PN BM74
J 2
(-5385 1485);
DISPLAY 0.489362 (-5385 1485);
PAINT MONO (-5385 1485);
FORCEPROP 0 LASTPIN (-5375 1375) $PN BR74
J 2
(-5385 1385);
DISPLAY 0.489362 (-5385 1385);
PAINT MONO (-5385 1385);
FORCEPROP 0 LASTPIN (-5375 3525) $PN BG73
J 2
(-5385 3535);
DISPLAY 0.489362 (-5385 3535);
PAINT MONO (-5385 3535);
FORCEPROP 0 LASTPIN (-5375 3475) $PN BH72
J 2
(-5385 3485);
DISPLAY 0.489362 (-5385 3485);
PAINT MONO (-5385 3485);
FORCEPROP 0 LASTPIN (-5375 3425) $PN BH74
J 2
(-5385 3435);
DISPLAY 0.489362 (-5385 3435);
PAINT MONO (-5385 3435);
FORCEPROP 0 LASTPIN (-5375 3375) $PN BJ74
J 2
(-5385 3385);
DISPLAY 0.489362 (-5385 3385);
PAINT MONO (-5385 3385);
FORCEPROP 0 LASTPIN (-5375 3325) $PN BJ73
J 2
(-5385 3335);
DISPLAY 0.489362 (-5385 3335);
PAINT MONO (-5385 3335);
FORCEPROP 0 LASTPIN (-5375 3275) $PN BK72
J 2
(-5385 3285);
DISPLAY 0.489362 (-5385 3285);
PAINT MONO (-5385 3285);
FORCEPROP 0 LASTPIN (-5375 3225) $PN BK74
J 2
(-5385 3235);
DISPLAY 0.489362 (-5385 3235);
PAINT MONO (-5385 3235);
FORCEPROP 0 LASTPIN (-3775 2025) $PN BY74
J 0
(-3765 2035);
DISPLAY 0.489362 (-3765 2035);
PAINT MONO (-3765 2035);
FORCEPROP 0 LASTPIN (-3775 1975) $PN CA73
J 0
(-3765 1985);
DISPLAY 0.489362 (-3765 1985);
PAINT MONO (-3765 1985);
FORCEPROP 0 LASTPIN (-3775 1925) $PN CA74
J 0
(-3765 1935);
DISPLAY 0.489362 (-3765 1935);
PAINT MONO (-3765 1935);
FORCEPROP 0 LASTPIN (-3775 1875) $PN CB72
J 0
(-3765 1885);
DISPLAY 0.489362 (-3765 1885);
PAINT MONO (-3765 1885);
FORCEPROP 0 LASTPIN (-3775 1825) $PN BT74
J 0
(-3765 1835);
DISPLAY 0.489362 (-3765 1835);
PAINT MONO (-3765 1835);
FORCEPROP 0 LASTPIN (-3775 1775) $PN BU73
J 0
(-3765 1785);
DISPLAY 0.489362 (-3765 1785);
PAINT MONO (-3765 1785);
FORCEPROP 0 LASTPIN (-3775 1725) $PN BU74
J 0
(-3765 1735);
DISPLAY 0.489362 (-3765 1735);
PAINT MONO (-3765 1735);
FORCEPROP 0 LASTPIN (-3775 1675) $PN BV72
J 0
(-3765 1685);
DISPLAY 0.489362 (-3765 1685);
PAINT MONO (-3765 1685);
FORCEPROP 0 LASTPIN (-3775 4275) $PN CB74
J 0
(-3765 4285);
DISPLAY 0.489362 (-3765 4285);
PAINT MONO (-3765 4285);
FORCEPROP 0 LASTPIN (-3775 4225) $PN CC73
J 0
(-3765 4235);
DISPLAY 0.489362 (-3765 4235);
PAINT MONO (-3765 4235);
FORCEPROP 0 LASTPIN (-3775 4175) $PN CC74
J 0
(-3765 4185);
DISPLAY 0.489362 (-3765 4185);
PAINT MONO (-3765 4185);
FORCEPROP 0 LASTPIN (-3775 4125) $PN CD72
J 0
(-3765 4135);
DISPLAY 0.489362 (-3765 4135);
PAINT MONO (-3765 4135);
FORCEPROP 0 LASTPIN (-3775 4075) $PN CF74
J 0
(-3765 4085);
DISPLAY 0.489362 (-3765 4085);
PAINT MONO (-3765 4085);
FORCEPROP 0 LASTPIN (-3775 4025) $PN CG73
J 0
(-3765 4035);
DISPLAY 0.489362 (-3765 4035);
PAINT MONO (-3765 4035);
FORCEPROP 0 LASTPIN (-3775 3975) $PN CG74
J 0
(-3765 3985);
DISPLAY 0.489362 (-3765 3985);
PAINT MONO (-3765 3985);
FORCEPROP 0 LASTPIN (-3775 3925) $PN CH72
J 0
(-3765 3935);
DISPLAY 0.489362 (-3765 3935);
PAINT MONO (-3765 3935);
FORCEPROP 0 LASTPIN (-3775 3825) $PN CH74
J 0
(-3765 3835);
DISPLAY 0.489362 (-3765 3835);
PAINT MONO (-3765 3835);
FORCEPROP 0 LASTPIN (-3775 3775) $PN CJ73
J 0
(-3765 3785);
DISPLAY 0.489362 (-3765 3785);
PAINT MONO (-3765 3785);
FORCEPROP 0 LASTPIN (-3775 3725) $PN CJ74
J 0
(-3765 3735);
DISPLAY 0.489362 (-3765 3735);
PAINT MONO (-3765 3735);
FORCEPROP 0 LASTPIN (-3775 3675) $PN CK72
J 0
(-3765 3685);
DISPLAY 0.489362 (-3765 3685);
PAINT MONO (-3765 3685);
FORCEPROP 0 LASTPIN (-3775 3625) $PN CM74
J 0
(-3765 3635);
DISPLAY 0.489362 (-3765 3635);
PAINT MONO (-3765 3635);
FORCEPROP 0 LASTPIN (-3775 3575) $PN CN73
J 0
(-3765 3585);
DISPLAY 0.489362 (-3765 3585);
PAINT MONO (-3765 3585);
FORCEPROP 0 LASTPIN (-3775 3525) $PN CN74
J 0
(-3765 3535);
DISPLAY 0.489362 (-3765 3535);
PAINT MONO (-3765 3535);
FORCEPROP 0 LASTPIN (-3775 3475) $PN CP72
J 0
(-3765 3485);
DISPLAY 0.489362 (-3765 3485);
PAINT MONO (-3765 3485);
FORCEPROP 0 LASTPIN (-3775 3375) $PN CP74
J 0
(-3765 3385);
DISPLAY 0.489362 (-3765 3385);
PAINT MONO (-3765 3385);
FORCEPROP 0 LASTPIN (-3775 3325) $PN CR73
J 0
(-3765 3335);
DISPLAY 0.489362 (-3765 3335);
PAINT MONO (-3765 3335);
FORCEPROP 0 LASTPIN (-3775 3275) $PN CR74
J 0
(-3765 3285);
DISPLAY 0.489362 (-3765 3285);
PAINT MONO (-3765 3285);
FORCEPROP 0 LASTPIN (-3775 3225) $PN CT72
J 0
(-3765 3235);
DISPLAY 0.489362 (-3765 3235);
PAINT MONO (-3765 3235);
FORCEPROP 0 LASTPIN (-3775 3175) $PN CV74
J 0
(-3765 3185);
DISPLAY 0.489362 (-3765 3185);
PAINT MONO (-3765 3185);
FORCEPROP 0 LASTPIN (-3775 3125) $PN CW73
J 0
(-3765 3135);
DISPLAY 0.489362 (-3765 3135);
PAINT MONO (-3765 3135);
FORCEPROP 0 LASTPIN (-3775 3075) $PN CW74
J 0
(-3765 3085);
DISPLAY 0.489362 (-3765 3085);
PAINT MONO (-3765 3085);
FORCEPROP 0 LASTPIN (-3775 3025) $PN CY72
J 0
(-3765 3035);
DISPLAY 0.489362 (-3765 3035);
PAINT MONO (-3765 3035);
FORCEPROP 0 LASTPIN (-3775 2925) $PN CY74
J 0
(-3765 2935);
DISPLAY 0.489362 (-3765 2935);
PAINT MONO (-3765 2935);
FORCEPROP 0 LASTPIN (-3775 2875) $PN DA73
J 0
(-3765 2885);
DISPLAY 0.489362 (-3765 2885);
PAINT MONO (-3765 2885);
FORCEPROP 0 LASTPIN (-3775 2825) $PN DA74
J 0
(-3765 2835);
DISPLAY 0.489362 (-3765 2835);
PAINT MONO (-3765 2835);
FORCEPROP 0 LASTPIN (-3775 2775) $PN DB72
J 0
(-3765 2785);
DISPLAY 0.489362 (-3765 2785);
PAINT MONO (-3765 2785);
FORCEPROP 0 LASTPIN (-3775 2725) $PN DD74
J 0
(-3765 2735);
DISPLAY 0.489362 (-3765 2735);
PAINT MONO (-3765 2735);
FORCEPROP 0 LASTPIN (-3775 2675) $PN DE73
J 0
(-3765 2685);
DISPLAY 0.489362 (-3765 2685);
PAINT MONO (-3765 2685);
FORCEPROP 0 LASTPIN (-3775 2625) $PN DE74
J 0
(-3765 2635);
DISPLAY 0.489362 (-3765 2635);
PAINT MONO (-3765 2635);
FORCEPROP 0 LASTPIN (-3775 2575) $PN DF74
J 0
(-3765 2585);
DISPLAY 0.489362 (-3765 2585);
PAINT MONO (-3765 2585);
FORCEPROP 0 LASTPIN (-5375 5025) $PN CD74
J 2
(-5385 5035);
DISPLAY 0.489362 (-5385 5035);
PAINT MONO (-5385 5035);
FORCEPROP 0 LASTPIN (-5375 4925) $PN CK74
J 2
(-5385 4935);
DISPLAY 0.489362 (-5385 4935);
PAINT MONO (-5385 4935);
FORCEPROP 0 LASTPIN (-5375 4825) $PN CT74
J 2
(-5385 4835);
DISPLAY 0.489362 (-5385 4835);
PAINT MONO (-5385 4835);
FORCEPROP 0 LASTPIN (-5375 4725) $PN DB74
J 2
(-5385 4735);
DISPLAY 0.489362 (-5385 4735);
PAINT MONO (-5385 4735);
FORCEPROP 0 LASTPIN (-5375 4625) $PN BY72
J 2
(-5385 4635);
DISPLAY 0.489362 (-5385 4635);
PAINT MONO (-5385 4635);
FORCEPROP 0 LASTPIN (-5375 4525) $PN CF72
J 2
(-5385 4535);
DISPLAY 0.489362 (-5385 4535);
PAINT MONO (-5385 4535);
FORCEPROP 0 LASTPIN (-5375 4425) $PN CM72
J 2
(-5385 4435);
DISPLAY 0.489362 (-5385 4435);
PAINT MONO (-5385 4435);
FORCEPROP 0 LASTPIN (-5375 4325) $PN CV72
J 2
(-5385 4335);
DISPLAY 0.489362 (-5385 4335);
PAINT MONO (-5385 4335);
FORCEPROP 0 LASTPIN (-5375 4225) $PN DD72
J 2
(-5385 4235);
DISPLAY 0.489362 (-5385 4235);
PAINT MONO (-5385 4235);
FORCEPROP 0 LASTPIN (-5375 4125) $PN BV74
J 2
(-5385 4135);
DISPLAY 0.489362 (-5385 4135);
PAINT MONO (-5385 4135);
FORCEPROP 0 LASTPIN (-5375 4975) $PN CE74
J 2
(-5385 4985);
DISPLAY 0.489362 (-5385 4985);
PAINT MONO (-5385 4985);
FORCEPROP 0 LASTPIN (-5375 4875) $PN CL74
J 2
(-5385 4885);
DISPLAY 0.489362 (-5385 4885);
PAINT MONO (-5385 4885);
FORCEPROP 0 LASTPIN (-5375 4775) $PN CU74
J 2
(-5385 4785);
DISPLAY 0.489362 (-5385 4785);
PAINT MONO (-5385 4785);
FORCEPROP 0 LASTPIN (-5375 4675) $PN DC74
J 2
(-5385 4685);
DISPLAY 0.489362 (-5385 4685);
PAINT MONO (-5385 4685);
FORCEPROP 0 LASTPIN (-5375 4575) $PN BW73
J 2
(-5385 4585);
DISPLAY 0.489362 (-5385 4585);
PAINT MONO (-5385 4585);
FORCEPROP 0 LASTPIN (-5375 4475) $PN CE73
J 2
(-5385 4485);
DISPLAY 0.489362 (-5385 4485);
PAINT MONO (-5385 4485);
FORCEPROP 0 LASTPIN (-5375 4375) $PN CL73
J 2
(-5385 4385);
DISPLAY 0.489362 (-5385 4385);
PAINT MONO (-5385 4385);
FORCEPROP 0 LASTPIN (-5375 4275) $PN CU73
J 2
(-5385 4285);
DISPLAY 0.489362 (-5385 4285);
PAINT MONO (-5385 4285);
FORCEPROP 0 LASTPIN (-5375 4175) $PN DC73
J 2
(-5385 4185);
DISPLAY 0.489362 (-5385 4185);
PAINT MONO (-5385 4185);
FORCEPROP 0 LASTPIN (-5375 4075) $PN BW74
J 2
(-5385 4085);
DISPLAY 0.489362 (-5385 4085);
PAINT MONO (-5385 4085);
FORCEPROP 0 LASTPIN (-5375 2325) $PN BL74
J 2
(-5385 2335);
DISPLAY 0.489362 (-5385 2335);
PAINT MONO (-5385 2335);
FORCEPROP 0 LASTPIN (-5375 1275) $PN BF72
J 2
(-5385 1285);
DISPLAY 0.489362 (-5385 1285);
PAINT MONO (-5385 1285);
FORCEPROP 0 LASTPIN (-5375 1225) $PN C60
J 2
(-5385 1235);
DISPLAY 0.489362 (-5385 1235);
PAINT MONO (-5385 1235);
FORCEPROP 2 LAST PART_TYPE SMLF
J 0
(-5225 6375);
DISPLAY 1.021277 (-5225 6375);
FORCEPROP 1 LAST MATERIAL IO
J 0
(-5220 6207);
DISPLAY 0.489362 (-5220 6207);
PAINT SKYBLUE (-5220 6207);
FORCEPROP 2 LAST VALUE SOCKET6096_13568-001
J 0
(-5225 6275);
DISPLAY 0.489362 (-5225 6275);
PAINT SKYBLUE (-5225 6275);
FORCEPROP 1 LAST PART_NUMBER DGA^6000030
J 0
(-5220 6334);
DISPLAY 0.489362 (-5220 6334);
PAINT SKYBLUE (-5220 6334);
FORCEPROP 2 LAST CDS_LIB pure_quanta
J 0
(-4575 3675);
DISPLAY INVISIBLE (-4575 3675);
FORCEPROP 1 LAST NEEDS_NO_SIZE TRUE
J 0
(-4575 3675);
DISPLAY 0.723404 (-4575 3675);
PAINT GREEN (-4575 3675);
DISPLAY INVISIBLE (-4575 3675);
FORCEPROP 1 LAST CDS_LMAN_SYM_OUTLINE -650,2500,650,-2500
J 0
(-4575 3675);
DISPLAY 0.468085 (-4575 3675);
PAINT GREEN (-4575 3675);
DISPLAY INVISIBLE (-4575 3675);
FORCEPROP 1 LAST PATH I167
J 0
(-4575 3675);
DISPLAY 0.723404 (-4575 3675);
PAINT GREEN (-4575 3675);
DISPLAY INVISIBLE (-4575 3675);
FORCEADD OFFPAGE..3
(-2575 6100);
FORCEPROP 2 LAST $XR0 97 
J 0
(-2361 6100);
DISPLAY 0.638298 (-2361 6100);
PAINT MONO (-2361 6100);
FORCEPROP 2 LAST PATH I168
J 0
(-2350 6150);
DISPLAY 1.021277 (-2350 6150);
DISPLAY INVISIBLE (-2350 6150);
FORCEPROP 1 LAST COMMENT_BODY TRUE
J 0
(-2625 6000);
DISPLAY 0.872340 (-2625 6000);
PAINT GREEN (-2625 6000);
DISPLAY INVISIBLE (-2625 6000);
FORCEPROP 1 LAST OFFPAGE TRUE
J 0
(-2250 5975);
DISPLAY 0.872340 (-2250 5975);
PAINT GREEN (-2250 5975);
DISPLAY INVISIBLE (-2250 5975);
FORCEPROP 2 LAST CDS_LIB mstr_standard
J 0
(-2575 6100);
DISPLAY 0.723404 (-2575 6100);
PAINT MONO (-2575 6100);
DISPLAY INVISIBLE (-2575 6100);
FORCEADD OFFPAGE..3
(-2575 4300);
FORCEPROP 2 LAST $XR0 97 
J 0
(-2361 4300);
DISPLAY 0.638298 (-2361 4300);
PAINT MONO (-2361 4300);
FORCEPROP 2 LAST PATH I169
J 0
(-2350 4350);
DISPLAY 1.021277 (-2350 4350);
DISPLAY INVISIBLE (-2350 4350);
FORCEPROP 1 LAST COMMENT_BODY TRUE
J 0
(-2625 4200);
DISPLAY 0.872340 (-2625 4200);
PAINT GREEN (-2625 4200);
DISPLAY INVISIBLE (-2625 4200);
FORCEPROP 1 LAST OFFPAGE TRUE
J 0
(-2250 4175);
DISPLAY 0.872340 (-2250 4175);
PAINT GREEN (-2250 4175);
DISPLAY INVISIBLE (-2250 4175);
FORCEPROP 2 LAST CDS_LIB mstr_standard
J 0
(-2575 4300);
DISPLAY 0.723404 (-2575 4300);
PAINT MONO (-2575 4300);
DISPLAY INVISIBLE (-2575 4300);
FORCEADD TAP..1
(-3300 6025);
FORCEPROP 3 LASTPIN (-3350 6025) SIG_NAME M_A_CPU1_SA_DQ<1>
J 0
(-3340 6035);
DISPLAY 0.659574 (-3340 6035);
PAINT MONO (-3340 6035);
DISPLAY INVISIBLE (-3340 6035);
FORCEPROP 1 LASTPIN (-3350 6025) BN 1
J 0
(-3362 6033);
DISPLAY 0.489362 (-3362 6033);
PAINT GREEN (-3362 6033);
FORCEPROP 2 LAST CDS_LIB mstr_standard
J 0
(-3300 6025);
DISPLAY 0.723404 (-3300 6025);
PAINT MONO (-3300 6025);
DISPLAY INVISIBLE (-3300 6025);
FORCEPROP 1 LAST BODY_TYPE PLUMBING
J 0
(-3300 6075);
DISPLAY 0.872340 (-3300 6075);
PAINT GREEN (-3300 6075);
DISPLAY INVISIBLE (-3300 6075);
FORCEPROP 1 LAST HDL_TAP TRUE
J 0
(-2975 5900);
DISPLAY 0.872340 (-2975 5900);
DISPLAY INVISIBLE (-2975 5900);
FORCEPROP 1 LAST PATH I170
J 0
(-3302 6025);
DISPLAY 0.872340 (-3302 6025);
PAINT GREEN (-3302 6025);
DISPLAY INVISIBLE (-3302 6025);
FORCEADD TAP..1
(-3300 6075);
FORCEPROP 3 LASTPIN (-3350 6075) SIG_NAME M_A_CPU1_SA_DQ<0>
J 0
(-3340 6085);
DISPLAY 0.659574 (-3340 6085);
PAINT MONO (-3340 6085);
DISPLAY INVISIBLE (-3340 6085);
FORCEPROP 1 LASTPIN (-3350 6075) BN 0
J 0
(-3362 6083);
DISPLAY 0.489362 (-3362 6083);
PAINT GREEN (-3362 6083);
FORCEPROP 2 LAST CDS_LIB mstr_standard
J 0
(-3300 6075);
DISPLAY 0.723404 (-3300 6075);
PAINT MONO (-3300 6075);
DISPLAY INVISIBLE (-3300 6075);
FORCEPROP 1 LAST BODY_TYPE PLUMBING
J 0
(-3300 6125);
DISPLAY 0.872340 (-3300 6125);
PAINT GREEN (-3300 6125);
DISPLAY INVISIBLE (-3300 6125);
FORCEPROP 1 LAST HDL_TAP TRUE
J 0
(-2975 5950);
DISPLAY 0.872340 (-2975 5950);
DISPLAY INVISIBLE (-2975 5950);
FORCEPROP 1 LAST PATH I171
J 0
(-3302 6075);
DISPLAY 0.872340 (-3302 6075);
PAINT GREEN (-3302 6075);
DISPLAY INVISIBLE (-3302 6075);
FORCEADD TAP..1
(-3300 5975);
FORCEPROP 3 LASTPIN (-3350 5975) SIG_NAME M_A_CPU1_SA_DQ<2>
J 0
(-3340 5985);
DISPLAY 0.659574 (-3340 5985);
PAINT MONO (-3340 5985);
DISPLAY INVISIBLE (-3340 5985);
FORCEPROP 1 LASTPIN (-3350 5975) BN 2
J 0
(-3362 5983);
DISPLAY 0.489362 (-3362 5983);
PAINT GREEN (-3362 5983);
FORCEPROP 2 LAST CDS_LIB mstr_standard
J 0
(-3300 5975);
DISPLAY 0.723404 (-3300 5975);
PAINT MONO (-3300 5975);
DISPLAY INVISIBLE (-3300 5975);
FORCEPROP 1 LAST BODY_TYPE PLUMBING
J 0
(-3300 6025);
DISPLAY 0.872340 (-3300 6025);
PAINT GREEN (-3300 6025);
DISPLAY INVISIBLE (-3300 6025);
FORCEPROP 1 LAST HDL_TAP TRUE
J 0
(-2975 5850);
DISPLAY 0.872340 (-2975 5850);
DISPLAY INVISIBLE (-2975 5850);
FORCEPROP 1 LAST PATH I172
J 0
(-3302 5975);
DISPLAY 0.872340 (-3302 5975);
PAINT GREEN (-3302 5975);
DISPLAY INVISIBLE (-3302 5975);
FORCEADD TAP..1
(-3300 5925);
FORCEPROP 3 LASTPIN (-3350 5925) SIG_NAME M_A_CPU1_SA_DQ<3>
J 0
(-3340 5935);
DISPLAY 0.659574 (-3340 5935);
PAINT MONO (-3340 5935);
DISPLAY INVISIBLE (-3340 5935);
FORCEPROP 1 LASTPIN (-3350 5925) BN 3
J 0
(-3362 5933);
DISPLAY 0.489362 (-3362 5933);
PAINT GREEN (-3362 5933);
FORCEPROP 2 LAST CDS_LIB mstr_standard
J 0
(-3300 5925);
DISPLAY 0.723404 (-3300 5925);
PAINT MONO (-3300 5925);
DISPLAY INVISIBLE (-3300 5925);
FORCEPROP 1 LAST BODY_TYPE PLUMBING
J 0
(-3300 5975);
DISPLAY 0.872340 (-3300 5975);
PAINT GREEN (-3300 5975);
DISPLAY INVISIBLE (-3300 5975);
FORCEPROP 1 LAST HDL_TAP TRUE
J 0
(-2975 5800);
DISPLAY 0.872340 (-2975 5800);
DISPLAY INVISIBLE (-2975 5800);
FORCEPROP 1 LAST PATH I173
J 0
(-3302 5925);
DISPLAY 0.872340 (-3302 5925);
PAINT GREEN (-3302 5925);
DISPLAY INVISIBLE (-3302 5925);
FORCEADD TAP..1
(-3300 5825);
FORCEPROP 3 LASTPIN (-3350 5825) SIG_NAME M_A_CPU1_SA_DQ<5>
J 0
(-3340 5835);
DISPLAY 0.659574 (-3340 5835);
PAINT MONO (-3340 5835);
DISPLAY INVISIBLE (-3340 5835);
FORCEPROP 1 LASTPIN (-3350 5825) BN 5
J 0
(-3362 5833);
DISPLAY 0.489362 (-3362 5833);
PAINT GREEN (-3362 5833);
FORCEPROP 2 LAST CDS_LIB mstr_standard
J 0
(-3300 5825);
DISPLAY 0.723404 (-3300 5825);
PAINT MONO (-3300 5825);
DISPLAY INVISIBLE (-3300 5825);
FORCEPROP 1 LAST BODY_TYPE PLUMBING
J 0
(-3300 5875);
DISPLAY 0.872340 (-3300 5875);
PAINT GREEN (-3300 5875);
DISPLAY INVISIBLE (-3300 5875);
FORCEPROP 1 LAST HDL_TAP TRUE
J 0
(-2975 5700);
DISPLAY 0.872340 (-2975 5700);
DISPLAY INVISIBLE (-2975 5700);
FORCEPROP 1 LAST PATH I174
J 0
(-3302 5825);
DISPLAY 0.872340 (-3302 5825);
PAINT GREEN (-3302 5825);
DISPLAY INVISIBLE (-3302 5825);
FORCEADD TAP..1
(-3300 5875);
FORCEPROP 3 LASTPIN (-3350 5875) SIG_NAME M_A_CPU1_SA_DQ<4>
J 0
(-3340 5885);
DISPLAY 0.659574 (-3340 5885);
PAINT MONO (-3340 5885);
DISPLAY INVISIBLE (-3340 5885);
FORCEPROP 1 LASTPIN (-3350 5875) BN 4
J 0
(-3362 5883);
DISPLAY 0.489362 (-3362 5883);
PAINT GREEN (-3362 5883);
FORCEPROP 2 LAST CDS_LIB mstr_standard
J 0
(-3300 5875);
DISPLAY 0.723404 (-3300 5875);
PAINT MONO (-3300 5875);
DISPLAY INVISIBLE (-3300 5875);
FORCEPROP 1 LAST BODY_TYPE PLUMBING
J 0
(-3300 5925);
DISPLAY 0.872340 (-3300 5925);
PAINT GREEN (-3300 5925);
DISPLAY INVISIBLE (-3300 5925);
FORCEPROP 1 LAST HDL_TAP TRUE
J 0
(-2975 5750);
DISPLAY 0.872340 (-2975 5750);
DISPLAY INVISIBLE (-2975 5750);
FORCEPROP 1 LAST PATH I175
J 0
(-3302 5875);
DISPLAY 0.872340 (-3302 5875);
PAINT GREEN (-3302 5875);
DISPLAY INVISIBLE (-3302 5875);
FORCEADD TAP..1
(-3300 5775);
FORCEPROP 3 LASTPIN (-3350 5775) SIG_NAME M_A_CPU1_SA_DQ<6>
J 0
(-3340 5785);
DISPLAY 0.659574 (-3340 5785);
PAINT MONO (-3340 5785);
DISPLAY INVISIBLE (-3340 5785);
FORCEPROP 1 LASTPIN (-3350 5775) BN 6
J 0
(-3362 5783);
DISPLAY 0.489362 (-3362 5783);
PAINT GREEN (-3362 5783);
FORCEPROP 2 LAST CDS_LIB mstr_standard
J 0
(-3300 5775);
DISPLAY 0.723404 (-3300 5775);
PAINT MONO (-3300 5775);
DISPLAY INVISIBLE (-3300 5775);
FORCEPROP 1 LAST BODY_TYPE PLUMBING
J 0
(-3300 5825);
DISPLAY 0.872340 (-3300 5825);
PAINT GREEN (-3300 5825);
DISPLAY INVISIBLE (-3300 5825);
FORCEPROP 1 LAST HDL_TAP TRUE
J 0
(-2975 5650);
DISPLAY 0.872340 (-2975 5650);
DISPLAY INVISIBLE (-2975 5650);
FORCEPROP 1 LAST PATH I176
J 0
(-3302 5775);
DISPLAY 0.872340 (-3302 5775);
PAINT GREEN (-3302 5775);
DISPLAY INVISIBLE (-3302 5775);
FORCEADD TAP..1
(-3300 5725);
FORCEPROP 3 LASTPIN (-3350 5725) SIG_NAME M_A_CPU1_SA_DQ<7>
J 0
(-3340 5735);
DISPLAY 0.659574 (-3340 5735);
PAINT MONO (-3340 5735);
DISPLAY INVISIBLE (-3340 5735);
FORCEPROP 1 LASTPIN (-3350 5725) BN 7
J 0
(-3362 5733);
DISPLAY 0.489362 (-3362 5733);
PAINT GREEN (-3362 5733);
FORCEPROP 2 LAST CDS_LIB mstr_standard
J 0
(-3300 5725);
DISPLAY 0.723404 (-3300 5725);
PAINT MONO (-3300 5725);
DISPLAY INVISIBLE (-3300 5725);
FORCEPROP 1 LAST BODY_TYPE PLUMBING
J 0
(-3300 5775);
DISPLAY 0.872340 (-3300 5775);
PAINT GREEN (-3300 5775);
DISPLAY INVISIBLE (-3300 5775);
FORCEPROP 1 LAST HDL_TAP TRUE
J 0
(-2975 5600);
DISPLAY 0.872340 (-2975 5600);
DISPLAY INVISIBLE (-2975 5600);
FORCEPROP 1 LAST PATH I177
J 0
(-3302 5725);
DISPLAY 0.872340 (-3302 5725);
PAINT GREEN (-3302 5725);
DISPLAY INVISIBLE (-3302 5725);
FORCEADD TAP..1
(-3300 5575);
FORCEPROP 3 LASTPIN (-3350 5575) SIG_NAME M_A_CPU1_SA_DQ<9>
J 0
(-3340 5585);
DISPLAY 0.659574 (-3340 5585);
PAINT MONO (-3340 5585);
DISPLAY INVISIBLE (-3340 5585);
FORCEPROP 1 LASTPIN (-3350 5575) BN 9
J 0
(-3362 5583);
DISPLAY 0.489362 (-3362 5583);
PAINT GREEN (-3362 5583);
FORCEPROP 2 LAST CDS_LIB mstr_standard
J 0
(-3300 5575);
DISPLAY 0.723404 (-3300 5575);
PAINT MONO (-3300 5575);
DISPLAY INVISIBLE (-3300 5575);
FORCEPROP 1 LAST BODY_TYPE PLUMBING
J 0
(-3300 5625);
DISPLAY 0.872340 (-3300 5625);
PAINT GREEN (-3300 5625);
DISPLAY INVISIBLE (-3300 5625);
FORCEPROP 1 LAST HDL_TAP TRUE
J 0
(-2975 5450);
DISPLAY 0.872340 (-2975 5450);
DISPLAY INVISIBLE (-2975 5450);
FORCEPROP 1 LAST PATH I178
J 0
(-3302 5575);
DISPLAY 0.872340 (-3302 5575);
PAINT GREEN (-3302 5575);
DISPLAY INVISIBLE (-3302 5575);
FORCEADD TAP..1
(-3300 5625);
FORCEPROP 3 LASTPIN (-3350 5625) SIG_NAME M_A_CPU1_SA_DQ<8>
J 0
(-3340 5635);
DISPLAY 0.659574 (-3340 5635);
PAINT MONO (-3340 5635);
DISPLAY INVISIBLE (-3340 5635);
FORCEPROP 1 LASTPIN (-3350 5625) BN 8
J 0
(-3362 5633);
DISPLAY 0.489362 (-3362 5633);
PAINT GREEN (-3362 5633);
FORCEPROP 2 LAST CDS_LIB mstr_standard
J 0
(-3300 5625);
DISPLAY 0.723404 (-3300 5625);
PAINT MONO (-3300 5625);
DISPLAY INVISIBLE (-3300 5625);
FORCEPROP 1 LAST BODY_TYPE PLUMBING
J 0
(-3300 5675);
DISPLAY 0.872340 (-3300 5675);
PAINT GREEN (-3300 5675);
DISPLAY INVISIBLE (-3300 5675);
FORCEPROP 1 LAST HDL_TAP TRUE
J 0
(-2975 5500);
DISPLAY 0.872340 (-2975 5500);
DISPLAY INVISIBLE (-2975 5500);
FORCEPROP 1 LAST PATH I179
J 0
(-3302 5625);
DISPLAY 0.872340 (-3302 5625);
PAINT GREEN (-3302 5625);
DISPLAY INVISIBLE (-3302 5625);
FORCEADD TAP..1
(-3300 5525);
FORCEPROP 3 LASTPIN (-3350 5525) SIG_NAME M_A_CPU1_SA_DQ<10>
J 0
(-3340 5535);
DISPLAY 0.659574 (-3340 5535);
PAINT MONO (-3340 5535);
DISPLAY INVISIBLE (-3340 5535);
FORCEPROP 1 LASTPIN (-3350 5525) BN 10
J 0
(-3362 5533);
DISPLAY 0.489362 (-3362 5533);
PAINT GREEN (-3362 5533);
FORCEPROP 2 LAST CDS_LIB mstr_standard
J 0
(-3300 5525);
DISPLAY 0.723404 (-3300 5525);
PAINT MONO (-3300 5525);
DISPLAY INVISIBLE (-3300 5525);
FORCEPROP 1 LAST BODY_TYPE PLUMBING
J 0
(-3300 5575);
DISPLAY 0.872340 (-3300 5575);
PAINT GREEN (-3300 5575);
DISPLAY INVISIBLE (-3300 5575);
FORCEPROP 1 LAST HDL_TAP TRUE
J 0
(-2975 5400);
DISPLAY 0.872340 (-2975 5400);
DISPLAY INVISIBLE (-2975 5400);
FORCEPROP 1 LAST PATH I180
J 0
(-3302 5525);
DISPLAY 0.872340 (-3302 5525);
PAINT GREEN (-3302 5525);
DISPLAY INVISIBLE (-3302 5525);
FORCEADD TAP..1
(-3300 5425);
FORCEPROP 3 LASTPIN (-3350 5425) SIG_NAME M_A_CPU1_SA_DQ<12>
J 0
(-3340 5435);
DISPLAY 0.659574 (-3340 5435);
PAINT MONO (-3340 5435);
DISPLAY INVISIBLE (-3340 5435);
FORCEPROP 1 LASTPIN (-3350 5425) BN 12
J 0
(-3362 5433);
DISPLAY 0.489362 (-3362 5433);
PAINT GREEN (-3362 5433);
FORCEPROP 2 LAST CDS_LIB mstr_standard
J 0
(-3300 5425);
DISPLAY 0.723404 (-3300 5425);
PAINT MONO (-3300 5425);
DISPLAY INVISIBLE (-3300 5425);
FORCEPROP 1 LAST BODY_TYPE PLUMBING
J 0
(-3300 5475);
DISPLAY 0.872340 (-3300 5475);
PAINT GREEN (-3300 5475);
DISPLAY INVISIBLE (-3300 5475);
FORCEPROP 1 LAST HDL_TAP TRUE
J 0
(-2975 5300);
DISPLAY 0.872340 (-2975 5300);
DISPLAY INVISIBLE (-2975 5300);
FORCEPROP 1 LAST PATH I181
J 0
(-3302 5425);
DISPLAY 0.872340 (-3302 5425);
PAINT GREEN (-3302 5425);
DISPLAY INVISIBLE (-3302 5425);
FORCEADD TAP..1
(-3300 5475);
FORCEPROP 3 LASTPIN (-3350 5475) SIG_NAME M_A_CPU1_SA_DQ<11>
J 0
(-3340 5485);
DISPLAY 0.659574 (-3340 5485);
PAINT MONO (-3340 5485);
DISPLAY INVISIBLE (-3340 5485);
FORCEPROP 1 LASTPIN (-3350 5475) BN 11
J 0
(-3362 5483);
DISPLAY 0.489362 (-3362 5483);
PAINT GREEN (-3362 5483);
FORCEPROP 2 LAST CDS_LIB mstr_standard
J 0
(-3300 5475);
DISPLAY 0.723404 (-3300 5475);
PAINT MONO (-3300 5475);
DISPLAY INVISIBLE (-3300 5475);
FORCEPROP 1 LAST BODY_TYPE PLUMBING
J 0
(-3300 5525);
DISPLAY 0.872340 (-3300 5525);
PAINT GREEN (-3300 5525);
DISPLAY INVISIBLE (-3300 5525);
FORCEPROP 1 LAST HDL_TAP TRUE
J 0
(-2975 5350);
DISPLAY 0.872340 (-2975 5350);
DISPLAY INVISIBLE (-2975 5350);
FORCEPROP 1 LAST PATH I182
J 0
(-3302 5475);
DISPLAY 0.872340 (-3302 5475);
PAINT GREEN (-3302 5475);
DISPLAY INVISIBLE (-3302 5475);
FORCEADD TAP..1
(-3300 5325);
FORCEPROP 3 LASTPIN (-3350 5325) SIG_NAME M_A_CPU1_SA_DQ<14>
J 0
(-3340 5335);
DISPLAY 0.659574 (-3340 5335);
PAINT MONO (-3340 5335);
DISPLAY INVISIBLE (-3340 5335);
FORCEPROP 1 LASTPIN (-3350 5325) BN 14
J 0
(-3362 5333);
DISPLAY 0.489362 (-3362 5333);
PAINT GREEN (-3362 5333);
FORCEPROP 2 LAST CDS_LIB mstr_standard
J 0
(-3300 5325);
DISPLAY 0.723404 (-3300 5325);
PAINT MONO (-3300 5325);
DISPLAY INVISIBLE (-3300 5325);
FORCEPROP 1 LAST BODY_TYPE PLUMBING
J 0
(-3300 5375);
DISPLAY 0.872340 (-3300 5375);
PAINT GREEN (-3300 5375);
DISPLAY INVISIBLE (-3300 5375);
FORCEPROP 1 LAST HDL_TAP TRUE
J 0
(-2975 5200);
DISPLAY 0.872340 (-2975 5200);
DISPLAY INVISIBLE (-2975 5200);
FORCEPROP 1 LAST PATH I183
J 0
(-3302 5325);
DISPLAY 0.872340 (-3302 5325);
PAINT GREEN (-3302 5325);
DISPLAY INVISIBLE (-3302 5325);
FORCEADD TAP..1
(-3300 5375);
FORCEPROP 3 LASTPIN (-3350 5375) SIG_NAME M_A_CPU1_SA_DQ<13>
J 0
(-3340 5385);
DISPLAY 0.659574 (-3340 5385);
PAINT MONO (-3340 5385);
DISPLAY INVISIBLE (-3340 5385);
FORCEPROP 1 LASTPIN (-3350 5375) BN 13
J 0
(-3362 5383);
DISPLAY 0.489362 (-3362 5383);
PAINT GREEN (-3362 5383);
FORCEPROP 2 LAST CDS_LIB mstr_standard
J 0
(-3300 5375);
DISPLAY 0.723404 (-3300 5375);
PAINT MONO (-3300 5375);
DISPLAY INVISIBLE (-3300 5375);
FORCEPROP 1 LAST BODY_TYPE PLUMBING
J 0
(-3300 5425);
DISPLAY 0.872340 (-3300 5425);
PAINT GREEN (-3300 5425);
DISPLAY INVISIBLE (-3300 5425);
FORCEPROP 1 LAST HDL_TAP TRUE
J 0
(-2975 5250);
DISPLAY 0.872340 (-2975 5250);
DISPLAY INVISIBLE (-2975 5250);
FORCEPROP 1 LAST PATH I184
J 0
(-3302 5375);
DISPLAY 0.872340 (-3302 5375);
PAINT GREEN (-3302 5375);
DISPLAY INVISIBLE (-3302 5375);
FORCEADD TAP..1
(-3300 5275);
FORCEPROP 3 LASTPIN (-3350 5275) SIG_NAME M_A_CPU1_SA_DQ<15>
J 0
(-3340 5285);
DISPLAY 0.659574 (-3340 5285);
PAINT MONO (-3340 5285);
DISPLAY INVISIBLE (-3340 5285);
FORCEPROP 1 LASTPIN (-3350 5275) BN 15
J 0
(-3362 5283);
DISPLAY 0.489362 (-3362 5283);
PAINT GREEN (-3362 5283);
FORCEPROP 2 LAST CDS_LIB mstr_standard
J 0
(-3300 5275);
DISPLAY 0.723404 (-3300 5275);
PAINT MONO (-3300 5275);
DISPLAY INVISIBLE (-3300 5275);
FORCEPROP 1 LAST BODY_TYPE PLUMBING
J 0
(-3300 5325);
DISPLAY 0.872340 (-3300 5325);
PAINT GREEN (-3300 5325);
DISPLAY INVISIBLE (-3300 5325);
FORCEPROP 1 LAST HDL_TAP TRUE
J 0
(-2975 5150);
DISPLAY 0.872340 (-2975 5150);
DISPLAY INVISIBLE (-2975 5150);
FORCEPROP 1 LAST PATH I185
J 0
(-3302 5275);
DISPLAY 0.872340 (-3302 5275);
PAINT GREEN (-3302 5275);
DISPLAY INVISIBLE (-3302 5275);
FORCEADD TAP..1
(-3300 5125);
FORCEPROP 3 LASTPIN (-3350 5125) SIG_NAME M_A_CPU1_SA_DQ<17>
J 0
(-3340 5135);
DISPLAY 0.659574 (-3340 5135);
PAINT MONO (-3340 5135);
DISPLAY INVISIBLE (-3340 5135);
FORCEPROP 1 LASTPIN (-3350 5125) BN 17
J 0
(-3362 5133);
DISPLAY 0.489362 (-3362 5133);
PAINT GREEN (-3362 5133);
FORCEPROP 2 LAST CDS_LIB mstr_standard
J 0
(-3300 5125);
DISPLAY 0.723404 (-3300 5125);
PAINT MONO (-3300 5125);
DISPLAY INVISIBLE (-3300 5125);
FORCEPROP 1 LAST BODY_TYPE PLUMBING
J 0
(-3300 5175);
DISPLAY 0.872340 (-3300 5175);
PAINT GREEN (-3300 5175);
DISPLAY INVISIBLE (-3300 5175);
FORCEPROP 1 LAST HDL_TAP TRUE
J 0
(-2975 5000);
DISPLAY 0.872340 (-2975 5000);
DISPLAY INVISIBLE (-2975 5000);
FORCEPROP 1 LAST PATH I186
J 0
(-3302 5125);
DISPLAY 0.872340 (-3302 5125);
PAINT GREEN (-3302 5125);
DISPLAY INVISIBLE (-3302 5125);
FORCEADD TAP..1
(-3300 5175);
FORCEPROP 3 LASTPIN (-3350 5175) SIG_NAME M_A_CPU1_SA_DQ<16>
J 0
(-3340 5185);
DISPLAY 0.659574 (-3340 5185);
PAINT MONO (-3340 5185);
DISPLAY INVISIBLE (-3340 5185);
FORCEPROP 1 LASTPIN (-3350 5175) BN 16
J 0
(-3362 5183);
DISPLAY 0.489362 (-3362 5183);
PAINT GREEN (-3362 5183);
FORCEPROP 2 LAST CDS_LIB mstr_standard
J 0
(-3300 5175);
DISPLAY 0.723404 (-3300 5175);
PAINT MONO (-3300 5175);
DISPLAY INVISIBLE (-3300 5175);
FORCEPROP 1 LAST BODY_TYPE PLUMBING
J 0
(-3300 5225);
DISPLAY 0.872340 (-3300 5225);
PAINT GREEN (-3300 5225);
DISPLAY INVISIBLE (-3300 5225);
FORCEPROP 1 LAST HDL_TAP TRUE
J 0
(-2975 5050);
DISPLAY 0.872340 (-2975 5050);
DISPLAY INVISIBLE (-2975 5050);
FORCEPROP 1 LAST PATH I187
J 0
(-3302 5175);
DISPLAY 0.872340 (-3302 5175);
PAINT GREEN (-3302 5175);
DISPLAY INVISIBLE (-3302 5175);
FORCEADD TAP..1
(-3300 5075);
FORCEPROP 3 LASTPIN (-3350 5075) SIG_NAME M_A_CPU1_SA_DQ<18>
J 0
(-3340 5085);
DISPLAY 0.659574 (-3340 5085);
PAINT MONO (-3340 5085);
DISPLAY INVISIBLE (-3340 5085);
FORCEPROP 1 LASTPIN (-3350 5075) BN 18
J 0
(-3362 5083);
DISPLAY 0.489362 (-3362 5083);
PAINT GREEN (-3362 5083);
FORCEPROP 2 LAST CDS_LIB mstr_standard
J 0
(-3300 5075);
DISPLAY 0.723404 (-3300 5075);
PAINT MONO (-3300 5075);
DISPLAY INVISIBLE (-3300 5075);
FORCEPROP 1 LAST BODY_TYPE PLUMBING
J 0
(-3300 5125);
DISPLAY 0.872340 (-3300 5125);
PAINT GREEN (-3300 5125);
DISPLAY INVISIBLE (-3300 5125);
FORCEPROP 1 LAST HDL_TAP TRUE
J 0
(-2975 4950);
DISPLAY 0.872340 (-2975 4950);
DISPLAY INVISIBLE (-2975 4950);
FORCEPROP 1 LAST PATH I188
J 0
(-3302 5075);
DISPLAY 0.872340 (-3302 5075);
PAINT GREEN (-3302 5075);
DISPLAY INVISIBLE (-3302 5075);
FORCEADD TAP..1
(-3300 5025);
FORCEPROP 3 LASTPIN (-3350 5025) SIG_NAME M_A_CPU1_SA_DQ<19>
J 0
(-3340 5035);
DISPLAY 0.659574 (-3340 5035);
PAINT MONO (-3340 5035);
DISPLAY INVISIBLE (-3340 5035);
FORCEPROP 1 LASTPIN (-3350 5025) BN 19
J 0
(-3362 5033);
DISPLAY 0.489362 (-3362 5033);
PAINT GREEN (-3362 5033);
FORCEPROP 2 LAST CDS_LIB mstr_standard
J 0
(-3300 5025);
DISPLAY 0.723404 (-3300 5025);
PAINT MONO (-3300 5025);
DISPLAY INVISIBLE (-3300 5025);
FORCEPROP 1 LAST BODY_TYPE PLUMBING
J 0
(-3300 5075);
DISPLAY 0.872340 (-3300 5075);
PAINT GREEN (-3300 5075);
DISPLAY INVISIBLE (-3300 5075);
FORCEPROP 1 LAST HDL_TAP TRUE
J 0
(-2975 4900);
DISPLAY 0.872340 (-2975 4900);
DISPLAY INVISIBLE (-2975 4900);
FORCEPROP 1 LAST PATH I189
J 0
(-3302 5025);
DISPLAY 0.872340 (-3302 5025);
PAINT GREEN (-3302 5025);
DISPLAY INVISIBLE (-3302 5025);
FORCEADD TAP..1
(-3300 4975);
FORCEPROP 3 LASTPIN (-3350 4975) SIG_NAME M_A_CPU1_SA_DQ<20>
J 0
(-3340 4985);
DISPLAY 0.659574 (-3340 4985);
PAINT MONO (-3340 4985);
DISPLAY INVISIBLE (-3340 4985);
FORCEPROP 1 LASTPIN (-3350 4975) BN 20
J 0
(-3362 4983);
DISPLAY 0.489362 (-3362 4983);
PAINT GREEN (-3362 4983);
FORCEPROP 2 LAST CDS_LIB mstr_standard
J 0
(-3300 4975);
DISPLAY 0.723404 (-3300 4975);
PAINT MONO (-3300 4975);
DISPLAY INVISIBLE (-3300 4975);
FORCEPROP 1 LAST BODY_TYPE PLUMBING
J 0
(-3300 5025);
DISPLAY 0.872340 (-3300 5025);
PAINT GREEN (-3300 5025);
DISPLAY INVISIBLE (-3300 5025);
FORCEPROP 1 LAST HDL_TAP TRUE
J 0
(-2975 4850);
DISPLAY 0.872340 (-2975 4850);
DISPLAY INVISIBLE (-2975 4850);
FORCEPROP 1 LAST PATH I190
J 0
(-3302 4975);
DISPLAY 0.872340 (-3302 4975);
PAINT GREEN (-3302 4975);
DISPLAY INVISIBLE (-3302 4975);
FORCEADD TAP..1
(-3300 4875);
FORCEPROP 3 LASTPIN (-3350 4875) SIG_NAME M_A_CPU1_SA_DQ<22>
J 0
(-3340 4885);
DISPLAY 0.659574 (-3340 4885);
PAINT MONO (-3340 4885);
DISPLAY INVISIBLE (-3340 4885);
FORCEPROP 1 LASTPIN (-3350 4875) BN 22
J 0
(-3362 4883);
DISPLAY 0.489362 (-3362 4883);
PAINT GREEN (-3362 4883);
FORCEPROP 2 LAST CDS_LIB mstr_standard
J 0
(-3300 4875);
DISPLAY 0.723404 (-3300 4875);
PAINT MONO (-3300 4875);
DISPLAY INVISIBLE (-3300 4875);
FORCEPROP 1 LAST BODY_TYPE PLUMBING
J 0
(-3300 4925);
DISPLAY 0.872340 (-3300 4925);
PAINT GREEN (-3300 4925);
DISPLAY INVISIBLE (-3300 4925);
FORCEPROP 1 LAST HDL_TAP TRUE
J 0
(-2975 4750);
DISPLAY 0.872340 (-2975 4750);
DISPLAY INVISIBLE (-2975 4750);
FORCEPROP 1 LAST PATH I191
J 0
(-3302 4875);
DISPLAY 0.872340 (-3302 4875);
PAINT GREEN (-3302 4875);
DISPLAY INVISIBLE (-3302 4875);
FORCEADD TAP..1
(-3300 4925);
FORCEPROP 3 LASTPIN (-3350 4925) SIG_NAME M_A_CPU1_SA_DQ<21>
J 0
(-3340 4935);
DISPLAY 0.659574 (-3340 4935);
PAINT MONO (-3340 4935);
DISPLAY INVISIBLE (-3340 4935);
FORCEPROP 1 LASTPIN (-3350 4925) BN 21
J 0
(-3362 4933);
DISPLAY 0.489362 (-3362 4933);
PAINT GREEN (-3362 4933);
FORCEPROP 2 LAST CDS_LIB mstr_standard
J 0
(-3300 4925);
DISPLAY 0.723404 (-3300 4925);
PAINT MONO (-3300 4925);
DISPLAY INVISIBLE (-3300 4925);
FORCEPROP 1 LAST BODY_TYPE PLUMBING
J 0
(-3300 4975);
DISPLAY 0.872340 (-3300 4975);
PAINT GREEN (-3300 4975);
DISPLAY INVISIBLE (-3300 4975);
FORCEPROP 1 LAST HDL_TAP TRUE
J 0
(-2975 4800);
DISPLAY 0.872340 (-2975 4800);
DISPLAY INVISIBLE (-2975 4800);
FORCEPROP 1 LAST PATH I192
J 0
(-3302 4925);
DISPLAY 0.872340 (-3302 4925);
PAINT GREEN (-3302 4925);
DISPLAY INVISIBLE (-3302 4925);
FORCEADD TAP..1
(-3300 4825);
FORCEPROP 3 LASTPIN (-3350 4825) SIG_NAME M_A_CPU1_SA_DQ<23>
J 0
(-3340 4835);
DISPLAY 0.659574 (-3340 4835);
PAINT MONO (-3340 4835);
DISPLAY INVISIBLE (-3340 4835);
FORCEPROP 1 LASTPIN (-3350 4825) BN 23
J 0
(-3362 4833);
DISPLAY 0.489362 (-3362 4833);
PAINT GREEN (-3362 4833);
FORCEPROP 2 LAST CDS_LIB mstr_standard
J 0
(-3300 4825);
DISPLAY 0.723404 (-3300 4825);
PAINT MONO (-3300 4825);
DISPLAY INVISIBLE (-3300 4825);
FORCEPROP 1 LAST BODY_TYPE PLUMBING
J 0
(-3300 4875);
DISPLAY 0.872340 (-3300 4875);
PAINT GREEN (-3300 4875);
DISPLAY INVISIBLE (-3300 4875);
FORCEPROP 1 LAST HDL_TAP TRUE
J 0
(-2975 4700);
DISPLAY 0.872340 (-2975 4700);
DISPLAY INVISIBLE (-2975 4700);
FORCEPROP 1 LAST PATH I193
J 0
(-3302 4825);
DISPLAY 0.872340 (-3302 4825);
PAINT GREEN (-3302 4825);
DISPLAY INVISIBLE (-3302 4825);
FORCEADD TAP..1
(-3300 4675);
FORCEPROP 3 LASTPIN (-3350 4675) SIG_NAME M_A_CPU1_SA_DQ<25>
J 0
(-3340 4685);
DISPLAY 0.659574 (-3340 4685);
PAINT MONO (-3340 4685);
DISPLAY INVISIBLE (-3340 4685);
FORCEPROP 1 LASTPIN (-3350 4675) BN 25
J 0
(-3362 4683);
DISPLAY 0.489362 (-3362 4683);
PAINT GREEN (-3362 4683);
FORCEPROP 2 LAST CDS_LIB mstr_standard
J 0
(-3300 4675);
DISPLAY 0.723404 (-3300 4675);
PAINT MONO (-3300 4675);
DISPLAY INVISIBLE (-3300 4675);
FORCEPROP 1 LAST BODY_TYPE PLUMBING
J 0
(-3300 4725);
DISPLAY 0.872340 (-3300 4725);
PAINT GREEN (-3300 4725);
DISPLAY INVISIBLE (-3300 4725);
FORCEPROP 1 LAST HDL_TAP TRUE
J 0
(-2975 4550);
DISPLAY 0.872340 (-2975 4550);
DISPLAY INVISIBLE (-2975 4550);
FORCEPROP 1 LAST PATH I194
J 0
(-3302 4675);
DISPLAY 0.872340 (-3302 4675);
PAINT GREEN (-3302 4675);
DISPLAY INVISIBLE (-3302 4675);
FORCEADD TAP..1
(-3300 4725);
FORCEPROP 3 LASTPIN (-3350 4725) SIG_NAME M_A_CPU1_SA_DQ<24>
J 0
(-3340 4735);
DISPLAY 0.659574 (-3340 4735);
PAINT MONO (-3340 4735);
DISPLAY INVISIBLE (-3340 4735);
FORCEPROP 1 LASTPIN (-3350 4725) BN 24
J 0
(-3362 4733);
DISPLAY 0.489362 (-3362 4733);
PAINT GREEN (-3362 4733);
FORCEPROP 2 LAST CDS_LIB mstr_standard
J 0
(-3300 4725);
DISPLAY 0.723404 (-3300 4725);
PAINT MONO (-3300 4725);
DISPLAY INVISIBLE (-3300 4725);
FORCEPROP 1 LAST BODY_TYPE PLUMBING
J 0
(-3300 4775);
DISPLAY 0.872340 (-3300 4775);
PAINT GREEN (-3300 4775);
DISPLAY INVISIBLE (-3300 4775);
FORCEPROP 1 LAST HDL_TAP TRUE
J 0
(-2975 4600);
DISPLAY 0.872340 (-2975 4600);
DISPLAY INVISIBLE (-2975 4600);
FORCEPROP 1 LAST PATH I195
J 0
(-3302 4725);
DISPLAY 0.872340 (-3302 4725);
PAINT GREEN (-3302 4725);
DISPLAY INVISIBLE (-3302 4725);
FORCEADD TAP..1
(-3300 4625);
FORCEPROP 3 LASTPIN (-3350 4625) SIG_NAME M_A_CPU1_SA_DQ<26>
J 0
(-3340 4635);
DISPLAY 0.659574 (-3340 4635);
PAINT MONO (-3340 4635);
DISPLAY INVISIBLE (-3340 4635);
FORCEPROP 1 LASTPIN (-3350 4625) BN 26
J 0
(-3362 4633);
DISPLAY 0.489362 (-3362 4633);
PAINT GREEN (-3362 4633);
FORCEPROP 2 LAST CDS_LIB mstr_standard
J 0
(-3300 4625);
DISPLAY 0.723404 (-3300 4625);
PAINT MONO (-3300 4625);
DISPLAY INVISIBLE (-3300 4625);
FORCEPROP 1 LAST BODY_TYPE PLUMBING
J 0
(-3300 4675);
DISPLAY 0.872340 (-3300 4675);
PAINT GREEN (-3300 4675);
DISPLAY INVISIBLE (-3300 4675);
FORCEPROP 1 LAST HDL_TAP TRUE
J 0
(-2975 4500);
DISPLAY 0.872340 (-2975 4500);
DISPLAY INVISIBLE (-2975 4500);
FORCEPROP 1 LAST PATH I196
J 0
(-3302 4625);
DISPLAY 0.872340 (-3302 4625);
PAINT GREEN (-3302 4625);
DISPLAY INVISIBLE (-3302 4625);
FORCEADD TAP..1
(-3300 4575);
FORCEPROP 3 LASTPIN (-3350 4575) SIG_NAME M_A_CPU1_SA_DQ<27>
J 0
(-3340 4585);
DISPLAY 0.659574 (-3340 4585);
PAINT MONO (-3340 4585);
DISPLAY INVISIBLE (-3340 4585);
FORCEPROP 1 LASTPIN (-3350 4575) BN 27
J 0
(-3362 4583);
DISPLAY 0.489362 (-3362 4583);
PAINT GREEN (-3362 4583);
FORCEPROP 2 LAST CDS_LIB mstr_standard
J 0
(-3300 4575);
DISPLAY 0.723404 (-3300 4575);
PAINT MONO (-3300 4575);
DISPLAY INVISIBLE (-3300 4575);
FORCEPROP 1 LAST BODY_TYPE PLUMBING
J 0
(-3300 4625);
DISPLAY 0.872340 (-3300 4625);
PAINT GREEN (-3300 4625);
DISPLAY INVISIBLE (-3300 4625);
FORCEPROP 1 LAST HDL_TAP TRUE
J 0
(-2975 4450);
DISPLAY 0.872340 (-2975 4450);
DISPLAY INVISIBLE (-2975 4450);
FORCEPROP 1 LAST PATH I197
J 0
(-3302 4575);
DISPLAY 0.872340 (-3302 4575);
PAINT GREEN (-3302 4575);
DISPLAY INVISIBLE (-3302 4575);
FORCEADD TAP..1
(-3300 4525);
FORCEPROP 3 LASTPIN (-3350 4525) SIG_NAME M_A_CPU1_SA_DQ<28>
J 0
(-3340 4535);
DISPLAY 0.659574 (-3340 4535);
PAINT MONO (-3340 4535);
DISPLAY INVISIBLE (-3340 4535);
FORCEPROP 1 LASTPIN (-3350 4525) BN 28
J 0
(-3362 4533);
DISPLAY 0.489362 (-3362 4533);
PAINT GREEN (-3362 4533);
FORCEPROP 2 LAST CDS_LIB mstr_standard
J 0
(-3300 4525);
DISPLAY 0.723404 (-3300 4525);
PAINT MONO (-3300 4525);
DISPLAY INVISIBLE (-3300 4525);
FORCEPROP 1 LAST BODY_TYPE PLUMBING
J 0
(-3300 4575);
DISPLAY 0.872340 (-3300 4575);
PAINT GREEN (-3300 4575);
DISPLAY INVISIBLE (-3300 4575);
FORCEPROP 1 LAST HDL_TAP TRUE
J 0
(-2975 4400);
DISPLAY 0.872340 (-2975 4400);
DISPLAY INVISIBLE (-2975 4400);
FORCEPROP 1 LAST PATH I198
J 0
(-3302 4525);
DISPLAY 0.872340 (-3302 4525);
PAINT GREEN (-3302 4525);
DISPLAY INVISIBLE (-3302 4525);
FORCEADD TAP..1
(-3300 4475);
FORCEPROP 3 LASTPIN (-3350 4475) SIG_NAME M_A_CPU1_SA_DQ<29>
J 0
(-3340 4485);
DISPLAY 0.659574 (-3340 4485);
PAINT MONO (-3340 4485);
DISPLAY INVISIBLE (-3340 4485);
FORCEPROP 1 LASTPIN (-3350 4475) BN 29
J 0
(-3362 4483);
DISPLAY 0.489362 (-3362 4483);
PAINT GREEN (-3362 4483);
FORCEPROP 2 LAST CDS_LIB mstr_standard
J 0
(-3300 4475);
DISPLAY 0.723404 (-3300 4475);
PAINT MONO (-3300 4475);
DISPLAY INVISIBLE (-3300 4475);
FORCEPROP 1 LAST BODY_TYPE PLUMBING
J 0
(-3300 4525);
DISPLAY 0.872340 (-3300 4525);
PAINT GREEN (-3300 4525);
DISPLAY INVISIBLE (-3300 4525);
FORCEPROP 1 LAST HDL_TAP TRUE
J 0
(-2975 4350);
DISPLAY 0.872340 (-2975 4350);
DISPLAY INVISIBLE (-2975 4350);
FORCEPROP 1 LAST PATH I199
J 0
(-3302 4475);
DISPLAY 0.872340 (-3302 4475);
PAINT GREEN (-3302 4475);
DISPLAY INVISIBLE (-3302 4475);
FORCEADD TAP..1
(-3300 4425);
FORCEPROP 3 LASTPIN (-3350 4425) SIG_NAME M_A_CPU1_SA_DQ<30>
J 0
(-3340 4435);
DISPLAY 0.659574 (-3340 4435);
PAINT MONO (-3340 4435);
DISPLAY INVISIBLE (-3340 4435);
FORCEPROP 1 LASTPIN (-3350 4425) BN 30
J 0
(-3362 4433);
DISPLAY 0.489362 (-3362 4433);
PAINT GREEN (-3362 4433);
FORCEPROP 2 LAST CDS_LIB mstr_standard
J 0
(-3300 4425);
DISPLAY 0.723404 (-3300 4425);
PAINT MONO (-3300 4425);
DISPLAY INVISIBLE (-3300 4425);
FORCEPROP 1 LAST BODY_TYPE PLUMBING
J 0
(-3300 4475);
DISPLAY 0.872340 (-3300 4475);
PAINT GREEN (-3300 4475);
DISPLAY INVISIBLE (-3300 4475);
FORCEPROP 1 LAST HDL_TAP TRUE
J 0
(-2975 4300);
DISPLAY 0.872340 (-2975 4300);
DISPLAY INVISIBLE (-2975 4300);
FORCEPROP 1 LAST PATH I200
J 0
(-3302 4425);
DISPLAY 0.872340 (-3302 4425);
PAINT GREEN (-3302 4425);
DISPLAY INVISIBLE (-3302 4425);
FORCEADD TAP..1
(-3300 4375);
FORCEPROP 3 LASTPIN (-3350 4375) SIG_NAME M_A_CPU1_SA_DQ<31>
J 0
(-3340 4385);
DISPLAY 0.659574 (-3340 4385);
PAINT MONO (-3340 4385);
DISPLAY INVISIBLE (-3340 4385);
FORCEPROP 1 LASTPIN (-3350 4375) BN 31
J 0
(-3362 4383);
DISPLAY 0.489362 (-3362 4383);
PAINT GREEN (-3362 4383);
FORCEPROP 2 LAST CDS_LIB mstr_standard
J 0
(-3300 4375);
DISPLAY 0.723404 (-3300 4375);
PAINT MONO (-3300 4375);
DISPLAY INVISIBLE (-3300 4375);
FORCEPROP 1 LAST BODY_TYPE PLUMBING
J 0
(-3300 4425);
DISPLAY 0.872340 (-3300 4425);
PAINT GREEN (-3300 4425);
DISPLAY INVISIBLE (-3300 4425);
FORCEPROP 1 LAST HDL_TAP TRUE
J 0
(-2975 4250);
DISPLAY 0.872340 (-2975 4250);
DISPLAY INVISIBLE (-2975 4250);
FORCEPROP 1 LAST PATH I201
J 0
(-3302 4375);
DISPLAY 0.872340 (-3302 4375);
PAINT GREEN (-3302 4375);
DISPLAY INVISIBLE (-3302 4375);
FORCEADD TAP..1
(-3300 4225);
FORCEPROP 3 LASTPIN (-3350 4225) SIG_NAME M_A_CPU1_SB_DQ<1>
J 0
(-3340 4235);
DISPLAY 0.659574 (-3340 4235);
PAINT MONO (-3340 4235);
DISPLAY INVISIBLE (-3340 4235);
FORCEPROP 1 LASTPIN (-3350 4225) BN 1
J 0
(-3362 4233);
DISPLAY 0.489362 (-3362 4233);
PAINT GREEN (-3362 4233);
FORCEPROP 2 LAST CDS_LIB mstr_standard
J 0
(-3300 4225);
DISPLAY 0.723404 (-3300 4225);
PAINT MONO (-3300 4225);
DISPLAY INVISIBLE (-3300 4225);
FORCEPROP 1 LAST BODY_TYPE PLUMBING
J 0
(-3300 4275);
DISPLAY 0.872340 (-3300 4275);
PAINT GREEN (-3300 4275);
DISPLAY INVISIBLE (-3300 4275);
FORCEPROP 1 LAST HDL_TAP TRUE
J 0
(-2975 4100);
DISPLAY 0.872340 (-2975 4100);
DISPLAY INVISIBLE (-2975 4100);
FORCEPROP 1 LAST PATH I202
J 0
(-3302 4225);
DISPLAY 0.872340 (-3302 4225);
PAINT GREEN (-3302 4225);
DISPLAY INVISIBLE (-3302 4225);
FORCEADD TAP..1
(-3300 4275);
FORCEPROP 3 LASTPIN (-3350 4275) SIG_NAME M_A_CPU1_SB_DQ<0>
J 0
(-3340 4285);
DISPLAY 0.659574 (-3340 4285);
PAINT MONO (-3340 4285);
DISPLAY INVISIBLE (-3340 4285);
FORCEPROP 1 LASTPIN (-3350 4275) BN 0
J 0
(-3362 4283);
DISPLAY 0.489362 (-3362 4283);
PAINT GREEN (-3362 4283);
FORCEPROP 2 LAST CDS_LIB mstr_standard
J 0
(-3300 4275);
DISPLAY 0.723404 (-3300 4275);
PAINT MONO (-3300 4275);
DISPLAY INVISIBLE (-3300 4275);
FORCEPROP 1 LAST BODY_TYPE PLUMBING
J 0
(-3300 4325);
DISPLAY 0.872340 (-3300 4325);
PAINT GREEN (-3300 4325);
DISPLAY INVISIBLE (-3300 4325);
FORCEPROP 1 LAST HDL_TAP TRUE
J 0
(-2975 4150);
DISPLAY 0.872340 (-2975 4150);
DISPLAY INVISIBLE (-2975 4150);
FORCEPROP 1 LAST PATH I203
J 0
(-3302 4275);
DISPLAY 0.872340 (-3302 4275);
PAINT GREEN (-3302 4275);
DISPLAY INVISIBLE (-3302 4275);
FORCEADD TAP..1
(-3300 4125);
FORCEPROP 3 LASTPIN (-3350 4125) SIG_NAME M_A_CPU1_SB_DQ<3>
J 0
(-3340 4135);
DISPLAY 0.659574 (-3340 4135);
PAINT MONO (-3340 4135);
DISPLAY INVISIBLE (-3340 4135);
FORCEPROP 1 LASTPIN (-3350 4125) BN 3
J 0
(-3362 4133);
DISPLAY 0.489362 (-3362 4133);
PAINT GREEN (-3362 4133);
FORCEPROP 2 LAST CDS_LIB mstr_standard
J 0
(-3300 4125);
DISPLAY 0.723404 (-3300 4125);
PAINT MONO (-3300 4125);
DISPLAY INVISIBLE (-3300 4125);
FORCEPROP 1 LAST BODY_TYPE PLUMBING
J 0
(-3300 4175);
DISPLAY 0.872340 (-3300 4175);
PAINT GREEN (-3300 4175);
DISPLAY INVISIBLE (-3300 4175);
FORCEPROP 1 LAST HDL_TAP TRUE
J 0
(-2975 4000);
DISPLAY 0.872340 (-2975 4000);
DISPLAY INVISIBLE (-2975 4000);
FORCEPROP 1 LAST PATH I204
J 0
(-3302 4125);
DISPLAY 0.872340 (-3302 4125);
PAINT GREEN (-3302 4125);
DISPLAY INVISIBLE (-3302 4125);
FORCEADD TAP..1
(-3300 4175);
FORCEPROP 3 LASTPIN (-3350 4175) SIG_NAME M_A_CPU1_SB_DQ<2>
J 0
(-3340 4185);
DISPLAY 0.659574 (-3340 4185);
PAINT MONO (-3340 4185);
DISPLAY INVISIBLE (-3340 4185);
FORCEPROP 1 LASTPIN (-3350 4175) BN 2
J 0
(-3362 4183);
DISPLAY 0.489362 (-3362 4183);
PAINT GREEN (-3362 4183);
FORCEPROP 2 LAST CDS_LIB mstr_standard
J 0
(-3300 4175);
DISPLAY 0.723404 (-3300 4175);
PAINT MONO (-3300 4175);
DISPLAY INVISIBLE (-3300 4175);
FORCEPROP 1 LAST BODY_TYPE PLUMBING
J 0
(-3300 4225);
DISPLAY 0.872340 (-3300 4225);
PAINT GREEN (-3300 4225);
DISPLAY INVISIBLE (-3300 4225);
FORCEPROP 1 LAST HDL_TAP TRUE
J 0
(-2975 4050);
DISPLAY 0.872340 (-2975 4050);
DISPLAY INVISIBLE (-2975 4050);
FORCEPROP 1 LAST PATH I205
J 0
(-3302 4175);
DISPLAY 0.872340 (-3302 4175);
PAINT GREEN (-3302 4175);
DISPLAY INVISIBLE (-3302 4175);
FORCEADD OFFPAGE..6
R 2
(-2700 2525);
FORCEPROP 2 LAST $XR0 97 
J 0
(-2486 2525);
DISPLAY 0.638298 (-2486 2525);
PAINT MONO (-2486 2525);
FORCEPROP 2 LAST PATH I206
J 0
(-2475 2575);
DISPLAY 1.021277 (-2475 2575);
DISPLAY INVISIBLE (-2475 2575);
FORCEPROP 1 LAST COMMENT_BODY TRUE
J 2
(-2800 2450);
DISPLAY 0.872340 (-2800 2450);
PAINT GREEN (-2800 2450);
DISPLAY INVISIBLE (-2800 2450);
FORCEPROP 1 LAST OFFPAGE TRUE
J 2
(-3025 2400);
DISPLAY 0.872340 (-3025 2400);
PAINT GREEN (-3025 2400);
DISPLAY INVISIBLE (-3025 2400);
FORCEPROP 2 LAST CDS_LIB mstr_standard
J 2
(-2700 2525);
DISPLAY 0.723404 (-2700 2525);
PAINT MONO (-2700 2525);
DISPLAY INVISIBLE (-2700 2525);
FORCEADD TAP..1
(-3300 4075);
FORCEPROP 3 LASTPIN (-3350 4075) SIG_NAME M_A_CPU1_SB_DQ<4>
J 0
(-3340 4085);
DISPLAY 0.659574 (-3340 4085);
PAINT MONO (-3340 4085);
DISPLAY INVISIBLE (-3340 4085);
FORCEPROP 1 LASTPIN (-3350 4075) BN 4
J 0
(-3362 4083);
DISPLAY 0.489362 (-3362 4083);
PAINT GREEN (-3362 4083);
FORCEPROP 2 LAST CDS_LIB mstr_standard
J 0
(-3300 4075);
DISPLAY 0.723404 (-3300 4075);
PAINT MONO (-3300 4075);
DISPLAY INVISIBLE (-3300 4075);
FORCEPROP 1 LAST BODY_TYPE PLUMBING
J 0
(-3300 4125);
DISPLAY 0.872340 (-3300 4125);
PAINT GREEN (-3300 4125);
DISPLAY INVISIBLE (-3300 4125);
FORCEPROP 1 LAST HDL_TAP TRUE
J 0
(-2975 3950);
DISPLAY 0.872340 (-2975 3950);
DISPLAY INVISIBLE (-2975 3950);
FORCEPROP 1 LAST PATH I207
J 0
(-3302 4075);
DISPLAY 0.872340 (-3302 4075);
PAINT GREEN (-3302 4075);
DISPLAY INVISIBLE (-3302 4075);
FORCEADD TAP..1
(-3300 3975);
FORCEPROP 3 LASTPIN (-3350 3975) SIG_NAME M_A_CPU1_SB_DQ<6>
J 0
(-3340 3985);
DISPLAY 0.659574 (-3340 3985);
PAINT MONO (-3340 3985);
DISPLAY INVISIBLE (-3340 3985);
FORCEPROP 1 LASTPIN (-3350 3975) BN 6
J 0
(-3362 3983);
DISPLAY 0.489362 (-3362 3983);
PAINT GREEN (-3362 3983);
FORCEPROP 2 LAST CDS_LIB mstr_standard
J 0
(-3300 3975);
DISPLAY 0.723404 (-3300 3975);
PAINT MONO (-3300 3975);
DISPLAY INVISIBLE (-3300 3975);
FORCEPROP 1 LAST BODY_TYPE PLUMBING
J 0
(-3300 4025);
DISPLAY 0.872340 (-3300 4025);
PAINT GREEN (-3300 4025);
DISPLAY INVISIBLE (-3300 4025);
FORCEPROP 1 LAST HDL_TAP TRUE
J 0
(-2975 3850);
DISPLAY 0.872340 (-2975 3850);
DISPLAY INVISIBLE (-2975 3850);
FORCEPROP 1 LAST PATH I208
J 0
(-3302 3975);
DISPLAY 0.872340 (-3302 3975);
PAINT GREEN (-3302 3975);
DISPLAY INVISIBLE (-3302 3975);
FORCEADD TAP..1
(-3300 4025);
FORCEPROP 3 LASTPIN (-3350 4025) SIG_NAME M_A_CPU1_SB_DQ<5>
J 0
(-3340 4035);
DISPLAY 0.659574 (-3340 4035);
PAINT MONO (-3340 4035);
DISPLAY INVISIBLE (-3340 4035);
FORCEPROP 1 LASTPIN (-3350 4025) BN 5
J 0
(-3362 4033);
DISPLAY 0.489362 (-3362 4033);
PAINT GREEN (-3362 4033);
FORCEPROP 2 LAST CDS_LIB mstr_standard
J 0
(-3300 4025);
DISPLAY 0.723404 (-3300 4025);
PAINT MONO (-3300 4025);
DISPLAY INVISIBLE (-3300 4025);
FORCEPROP 1 LAST BODY_TYPE PLUMBING
J 0
(-3300 4075);
DISPLAY 0.872340 (-3300 4075);
PAINT GREEN (-3300 4075);
DISPLAY INVISIBLE (-3300 4075);
FORCEPROP 1 LAST HDL_TAP TRUE
J 0
(-2975 3900);
DISPLAY 0.872340 (-2975 3900);
DISPLAY INVISIBLE (-2975 3900);
FORCEPROP 1 LAST PATH I209
J 0
(-3302 4025);
DISPLAY 0.872340 (-3302 4025);
PAINT GREEN (-3302 4025);
DISPLAY INVISIBLE (-3302 4025);
FORCEADD TAP..1
(-3300 3925);
FORCEPROP 3 LASTPIN (-3350 3925) SIG_NAME M_A_CPU1_SB_DQ<7>
J 0
(-3340 3935);
DISPLAY 0.659574 (-3340 3935);
PAINT MONO (-3340 3935);
DISPLAY INVISIBLE (-3340 3935);
FORCEPROP 1 LASTPIN (-3350 3925) BN 7
J 0
(-3362 3933);
DISPLAY 0.489362 (-3362 3933);
PAINT GREEN (-3362 3933);
FORCEPROP 2 LAST CDS_LIB mstr_standard
J 0
(-3300 3925);
DISPLAY 0.723404 (-3300 3925);
PAINT MONO (-3300 3925);
DISPLAY INVISIBLE (-3300 3925);
FORCEPROP 1 LAST BODY_TYPE PLUMBING
J 0
(-3300 3975);
DISPLAY 0.872340 (-3300 3975);
PAINT GREEN (-3300 3975);
DISPLAY INVISIBLE (-3300 3975);
FORCEPROP 1 LAST HDL_TAP TRUE
J 0
(-2975 3800);
DISPLAY 0.872340 (-2975 3800);
DISPLAY INVISIBLE (-2975 3800);
FORCEPROP 1 LAST PATH I210
J 0
(-3302 3925);
DISPLAY 0.872340 (-3302 3925);
PAINT GREEN (-3302 3925);
DISPLAY INVISIBLE (-3302 3925);
FORCEADD TAP..1
(-3300 3825);
FORCEPROP 3 LASTPIN (-3350 3825) SIG_NAME M_A_CPU1_SB_DQ<8>
J 0
(-3340 3835);
DISPLAY 0.659574 (-3340 3835);
PAINT MONO (-3340 3835);
DISPLAY INVISIBLE (-3340 3835);
FORCEPROP 1 LASTPIN (-3350 3825) BN 8
J 0
(-3362 3833);
DISPLAY 0.489362 (-3362 3833);
PAINT GREEN (-3362 3833);
FORCEPROP 2 LAST CDS_LIB mstr_standard
J 0
(-3300 3825);
DISPLAY 0.723404 (-3300 3825);
PAINT MONO (-3300 3825);
DISPLAY INVISIBLE (-3300 3825);
FORCEPROP 1 LAST BODY_TYPE PLUMBING
J 0
(-3300 3875);
DISPLAY 0.872340 (-3300 3875);
PAINT GREEN (-3300 3875);
DISPLAY INVISIBLE (-3300 3875);
FORCEPROP 1 LAST HDL_TAP TRUE
J 0
(-2975 3700);
DISPLAY 0.872340 (-2975 3700);
DISPLAY INVISIBLE (-2975 3700);
FORCEPROP 1 LAST PATH I211
J 0
(-3302 3825);
DISPLAY 0.872340 (-3302 3825);
PAINT GREEN (-3302 3825);
DISPLAY INVISIBLE (-3302 3825);
FORCEADD TAP..1
(-3300 3725);
FORCEPROP 3 LASTPIN (-3350 3725) SIG_NAME M_A_CPU1_SB_DQ<10>
J 0
(-3340 3735);
DISPLAY 0.659574 (-3340 3735);
PAINT MONO (-3340 3735);
DISPLAY INVISIBLE (-3340 3735);
FORCEPROP 1 LASTPIN (-3350 3725) BN 10
J 0
(-3362 3733);
DISPLAY 0.489362 (-3362 3733);
PAINT GREEN (-3362 3733);
FORCEPROP 2 LAST CDS_LIB mstr_standard
J 0
(-3300 3725);
DISPLAY 0.723404 (-3300 3725);
PAINT MONO (-3300 3725);
DISPLAY INVISIBLE (-3300 3725);
FORCEPROP 1 LAST BODY_TYPE PLUMBING
J 0
(-3300 3775);
DISPLAY 0.872340 (-3300 3775);
PAINT GREEN (-3300 3775);
DISPLAY INVISIBLE (-3300 3775);
FORCEPROP 1 LAST HDL_TAP TRUE
J 0
(-2975 3600);
DISPLAY 0.872340 (-2975 3600);
DISPLAY INVISIBLE (-2975 3600);
FORCEPROP 1 LAST PATH I212
J 0
(-3302 3725);
DISPLAY 0.872340 (-3302 3725);
PAINT GREEN (-3302 3725);
DISPLAY INVISIBLE (-3302 3725);
FORCEADD TAP..1
(-3300 3775);
FORCEPROP 3 LASTPIN (-3350 3775) SIG_NAME M_A_CPU1_SB_DQ<9>
J 0
(-3340 3785);
DISPLAY 0.659574 (-3340 3785);
PAINT MONO (-3340 3785);
DISPLAY INVISIBLE (-3340 3785);
FORCEPROP 1 LASTPIN (-3350 3775) BN 9
J 0
(-3362 3783);
DISPLAY 0.489362 (-3362 3783);
PAINT GREEN (-3362 3783);
FORCEPROP 2 LAST CDS_LIB mstr_standard
J 0
(-3300 3775);
DISPLAY 0.723404 (-3300 3775);
PAINT MONO (-3300 3775);
DISPLAY INVISIBLE (-3300 3775);
FORCEPROP 1 LAST BODY_TYPE PLUMBING
J 0
(-3300 3825);
DISPLAY 0.872340 (-3300 3825);
PAINT GREEN (-3300 3825);
DISPLAY INVISIBLE (-3300 3825);
FORCEPROP 1 LAST HDL_TAP TRUE
J 0
(-2975 3650);
DISPLAY 0.872340 (-2975 3650);
DISPLAY INVISIBLE (-2975 3650);
FORCEPROP 1 LAST PATH I213
J 0
(-3302 3775);
DISPLAY 0.872340 (-3302 3775);
PAINT GREEN (-3302 3775);
DISPLAY INVISIBLE (-3302 3775);
FORCEADD TAP..1
(-3300 3675);
FORCEPROP 3 LASTPIN (-3350 3675) SIG_NAME M_A_CPU1_SB_DQ<11>
J 0
(-3340 3685);
DISPLAY 0.659574 (-3340 3685);
PAINT MONO (-3340 3685);
DISPLAY INVISIBLE (-3340 3685);
FORCEPROP 1 LASTPIN (-3350 3675) BN 11
J 0
(-3362 3683);
DISPLAY 0.489362 (-3362 3683);
PAINT GREEN (-3362 3683);
FORCEPROP 2 LAST CDS_LIB mstr_standard
J 0
(-3300 3675);
DISPLAY 0.723404 (-3300 3675);
PAINT MONO (-3300 3675);
DISPLAY INVISIBLE (-3300 3675);
FORCEPROP 1 LAST BODY_TYPE PLUMBING
J 0
(-3300 3725);
DISPLAY 0.872340 (-3300 3725);
PAINT GREEN (-3300 3725);
DISPLAY INVISIBLE (-3300 3725);
FORCEPROP 1 LAST HDL_TAP TRUE
J 0
(-2975 3550);
DISPLAY 0.872340 (-2975 3550);
DISPLAY INVISIBLE (-2975 3550);
FORCEPROP 1 LAST PATH I214
J 0
(-3302 3675);
DISPLAY 0.872340 (-3302 3675);
PAINT GREEN (-3302 3675);
DISPLAY INVISIBLE (-3302 3675);
FORCEADD TAP..1
(-3300 3625);
FORCEPROP 3 LASTPIN (-3350 3625) SIG_NAME M_A_CPU1_SB_DQ<12>
J 0
(-3340 3635);
DISPLAY 0.659574 (-3340 3635);
PAINT MONO (-3340 3635);
DISPLAY INVISIBLE (-3340 3635);
FORCEPROP 1 LASTPIN (-3350 3625) BN 12
J 0
(-3362 3633);
DISPLAY 0.489362 (-3362 3633);
PAINT GREEN (-3362 3633);
FORCEPROP 2 LAST CDS_LIB mstr_standard
J 0
(-3300 3625);
DISPLAY 0.723404 (-3300 3625);
PAINT MONO (-3300 3625);
DISPLAY INVISIBLE (-3300 3625);
FORCEPROP 1 LAST BODY_TYPE PLUMBING
J 0
(-3300 3675);
DISPLAY 0.872340 (-3300 3675);
PAINT GREEN (-3300 3675);
DISPLAY INVISIBLE (-3300 3675);
FORCEPROP 1 LAST HDL_TAP TRUE
J 0
(-2975 3500);
DISPLAY 0.872340 (-2975 3500);
DISPLAY INVISIBLE (-2975 3500);
FORCEPROP 1 LAST PATH I215
J 0
(-3302 3625);
DISPLAY 0.872340 (-3302 3625);
PAINT GREEN (-3302 3625);
DISPLAY INVISIBLE (-3302 3625);
FORCEADD TAP..1
(-3300 3525);
FORCEPROP 3 LASTPIN (-3350 3525) SIG_NAME M_A_CPU1_SB_DQ<14>
J 0
(-3340 3535);
DISPLAY 0.659574 (-3340 3535);
PAINT MONO (-3340 3535);
DISPLAY INVISIBLE (-3340 3535);
FORCEPROP 1 LASTPIN (-3350 3525) BN 14
J 0
(-3362 3533);
DISPLAY 0.489362 (-3362 3533);
PAINT GREEN (-3362 3533);
FORCEPROP 2 LAST CDS_LIB mstr_standard
J 0
(-3300 3525);
DISPLAY 0.723404 (-3300 3525);
PAINT MONO (-3300 3525);
DISPLAY INVISIBLE (-3300 3525);
FORCEPROP 1 LAST BODY_TYPE PLUMBING
J 0
(-3300 3575);
DISPLAY 0.872340 (-3300 3575);
PAINT GREEN (-3300 3575);
DISPLAY INVISIBLE (-3300 3575);
FORCEPROP 1 LAST HDL_TAP TRUE
J 0
(-2975 3400);
DISPLAY 0.872340 (-2975 3400);
DISPLAY INVISIBLE (-2975 3400);
FORCEPROP 1 LAST PATH I216
J 0
(-3302 3525);
DISPLAY 0.872340 (-3302 3525);
PAINT GREEN (-3302 3525);
DISPLAY INVISIBLE (-3302 3525);
FORCEADD TAP..1
(-3300 3575);
FORCEPROP 3 LASTPIN (-3350 3575) SIG_NAME M_A_CPU1_SB_DQ<13>
J 0
(-3340 3585);
DISPLAY 0.659574 (-3340 3585);
PAINT MONO (-3340 3585);
DISPLAY INVISIBLE (-3340 3585);
FORCEPROP 1 LASTPIN (-3350 3575) BN 13
J 0
(-3362 3583);
DISPLAY 0.489362 (-3362 3583);
PAINT GREEN (-3362 3583);
FORCEPROP 2 LAST CDS_LIB mstr_standard
J 0
(-3300 3575);
DISPLAY 0.723404 (-3300 3575);
PAINT MONO (-3300 3575);
DISPLAY INVISIBLE (-3300 3575);
FORCEPROP 1 LAST BODY_TYPE PLUMBING
J 0
(-3300 3625);
DISPLAY 0.872340 (-3300 3625);
PAINT GREEN (-3300 3625);
DISPLAY INVISIBLE (-3300 3625);
FORCEPROP 1 LAST HDL_TAP TRUE
J 0
(-2975 3450);
DISPLAY 0.872340 (-2975 3450);
DISPLAY INVISIBLE (-2975 3450);
FORCEPROP 1 LAST PATH I217
J 0
(-3302 3575);
DISPLAY 0.872340 (-3302 3575);
PAINT GREEN (-3302 3575);
DISPLAY INVISIBLE (-3302 3575);
FORCEADD TAP..1
(-3300 3475);
FORCEPROP 3 LASTPIN (-3350 3475) SIG_NAME M_A_CPU1_SB_DQ<15>
J 0
(-3340 3485);
DISPLAY 0.659574 (-3340 3485);
PAINT MONO (-3340 3485);
DISPLAY INVISIBLE (-3340 3485);
FORCEPROP 1 LASTPIN (-3350 3475) BN 15
J 0
(-3362 3483);
DISPLAY 0.489362 (-3362 3483);
PAINT GREEN (-3362 3483);
FORCEPROP 2 LAST CDS_LIB mstr_standard
J 0
(-3300 3475);
DISPLAY 0.723404 (-3300 3475);
PAINT MONO (-3300 3475);
DISPLAY INVISIBLE (-3300 3475);
FORCEPROP 1 LAST BODY_TYPE PLUMBING
J 0
(-3300 3525);
DISPLAY 0.872340 (-3300 3525);
PAINT GREEN (-3300 3525);
DISPLAY INVISIBLE (-3300 3525);
FORCEPROP 1 LAST HDL_TAP TRUE
J 0
(-2975 3350);
DISPLAY 0.872340 (-2975 3350);
DISPLAY INVISIBLE (-2975 3350);
FORCEPROP 1 LAST PATH I218
J 0
(-3302 3475);
DISPLAY 0.872340 (-3302 3475);
PAINT GREEN (-3302 3475);
DISPLAY INVISIBLE (-3302 3475);
FORCEADD TAP..1
(-3300 3375);
FORCEPROP 3 LASTPIN (-3350 3375) SIG_NAME M_A_CPU1_SB_DQ<16>
J 0
(-3340 3385);
DISPLAY 0.659574 (-3340 3385);
PAINT MONO (-3340 3385);
DISPLAY INVISIBLE (-3340 3385);
FORCEPROP 1 LASTPIN (-3350 3375) BN 16
J 0
(-3362 3383);
DISPLAY 0.489362 (-3362 3383);
PAINT GREEN (-3362 3383);
FORCEPROP 2 LAST CDS_LIB mstr_standard
J 0
(-3300 3375);
DISPLAY 0.723404 (-3300 3375);
PAINT MONO (-3300 3375);
DISPLAY INVISIBLE (-3300 3375);
FORCEPROP 1 LAST BODY_TYPE PLUMBING
J 0
(-3300 3425);
DISPLAY 0.872340 (-3300 3425);
PAINT GREEN (-3300 3425);
DISPLAY INVISIBLE (-3300 3425);
FORCEPROP 1 LAST HDL_TAP TRUE
J 0
(-2975 3250);
DISPLAY 0.872340 (-2975 3250);
DISPLAY INVISIBLE (-2975 3250);
FORCEPROP 1 LAST PATH I219
J 0
(-3302 3375);
DISPLAY 0.872340 (-3302 3375);
PAINT GREEN (-3302 3375);
DISPLAY INVISIBLE (-3302 3375);
FORCEADD TAP..1
(-3300 3275);
FORCEPROP 3 LASTPIN (-3350 3275) SIG_NAME M_A_CPU1_SB_DQ<18>
J 0
(-3340 3285);
DISPLAY 0.659574 (-3340 3285);
PAINT MONO (-3340 3285);
DISPLAY INVISIBLE (-3340 3285);
FORCEPROP 1 LASTPIN (-3350 3275) BN 18
J 0
(-3362 3283);
DISPLAY 0.489362 (-3362 3283);
PAINT GREEN (-3362 3283);
FORCEPROP 2 LAST CDS_LIB mstr_standard
J 0
(-3300 3275);
DISPLAY 0.723404 (-3300 3275);
PAINT MONO (-3300 3275);
DISPLAY INVISIBLE (-3300 3275);
FORCEPROP 1 LAST BODY_TYPE PLUMBING
J 0
(-3300 3325);
DISPLAY 0.872340 (-3300 3325);
PAINT GREEN (-3300 3325);
DISPLAY INVISIBLE (-3300 3325);
FORCEPROP 1 LAST HDL_TAP TRUE
J 0
(-2975 3150);
DISPLAY 0.872340 (-2975 3150);
DISPLAY INVISIBLE (-2975 3150);
FORCEPROP 1 LAST PATH I220
J 0
(-3302 3275);
DISPLAY 0.872340 (-3302 3275);
PAINT GREEN (-3302 3275);
DISPLAY INVISIBLE (-3302 3275);
FORCEADD TAP..1
(-3300 3325);
FORCEPROP 3 LASTPIN (-3350 3325) SIG_NAME M_A_CPU1_SB_DQ<17>
J 0
(-3340 3335);
DISPLAY 0.659574 (-3340 3335);
PAINT MONO (-3340 3335);
DISPLAY INVISIBLE (-3340 3335);
FORCEPROP 1 LASTPIN (-3350 3325) BN 17
J 0
(-3362 3333);
DISPLAY 0.489362 (-3362 3333);
PAINT GREEN (-3362 3333);
FORCEPROP 2 LAST CDS_LIB mstr_standard
J 0
(-3300 3325);
DISPLAY 0.723404 (-3300 3325);
PAINT MONO (-3300 3325);
DISPLAY INVISIBLE (-3300 3325);
FORCEPROP 1 LAST BODY_TYPE PLUMBING
J 0
(-3300 3375);
DISPLAY 0.872340 (-3300 3375);
PAINT GREEN (-3300 3375);
DISPLAY INVISIBLE (-3300 3375);
FORCEPROP 1 LAST HDL_TAP TRUE
J 0
(-2975 3200);
DISPLAY 0.872340 (-2975 3200);
DISPLAY INVISIBLE (-2975 3200);
FORCEPROP 1 LAST PATH I221
J 0
(-3302 3325);
DISPLAY 0.872340 (-3302 3325);
PAINT GREEN (-3302 3325);
DISPLAY INVISIBLE (-3302 3325);
FORCEADD TAP..1
(-3300 3225);
FORCEPROP 3 LASTPIN (-3350 3225) SIG_NAME M_A_CPU1_SB_DQ<19>
J 0
(-3340 3235);
DISPLAY 0.659574 (-3340 3235);
PAINT MONO (-3340 3235);
DISPLAY INVISIBLE (-3340 3235);
FORCEPROP 1 LASTPIN (-3350 3225) BN 19
J 0
(-3362 3233);
DISPLAY 0.489362 (-3362 3233);
PAINT GREEN (-3362 3233);
FORCEPROP 2 LAST CDS_LIB mstr_standard
J 0
(-3300 3225);
DISPLAY 0.723404 (-3300 3225);
PAINT MONO (-3300 3225);
DISPLAY INVISIBLE (-3300 3225);
FORCEPROP 1 LAST BODY_TYPE PLUMBING
J 0
(-3300 3275);
DISPLAY 0.872340 (-3300 3275);
PAINT GREEN (-3300 3275);
DISPLAY INVISIBLE (-3300 3275);
FORCEPROP 1 LAST HDL_TAP TRUE
J 0
(-2975 3100);
DISPLAY 0.872340 (-2975 3100);
DISPLAY INVISIBLE (-2975 3100);
FORCEPROP 1 LAST PATH I222
J 0
(-3302 3225);
DISPLAY 0.872340 (-3302 3225);
PAINT GREEN (-3302 3225);
DISPLAY INVISIBLE (-3302 3225);
FORCEADD TAP..1
(-3300 3175);
FORCEPROP 3 LASTPIN (-3350 3175) SIG_NAME M_A_CPU1_SB_DQ<20>
J 0
(-3340 3185);
DISPLAY 0.659574 (-3340 3185);
PAINT MONO (-3340 3185);
DISPLAY INVISIBLE (-3340 3185);
FORCEPROP 1 LASTPIN (-3350 3175) BN 20
J 0
(-3362 3183);
DISPLAY 0.489362 (-3362 3183);
PAINT GREEN (-3362 3183);
FORCEPROP 2 LAST CDS_LIB mstr_standard
J 0
(-3300 3175);
DISPLAY 0.723404 (-3300 3175);
PAINT MONO (-3300 3175);
DISPLAY INVISIBLE (-3300 3175);
FORCEPROP 1 LAST BODY_TYPE PLUMBING
J 0
(-3300 3225);
DISPLAY 0.872340 (-3300 3225);
PAINT GREEN (-3300 3225);
DISPLAY INVISIBLE (-3300 3225);
FORCEPROP 1 LAST HDL_TAP TRUE
J 0
(-2975 3050);
DISPLAY 0.872340 (-2975 3050);
DISPLAY INVISIBLE (-2975 3050);
FORCEPROP 1 LAST PATH I223
J 0
(-3302 3175);
DISPLAY 0.872340 (-3302 3175);
PAINT GREEN (-3302 3175);
DISPLAY INVISIBLE (-3302 3175);
FORCEADD TAP..1
(-3300 3125);
FORCEPROP 3 LASTPIN (-3350 3125) SIG_NAME M_A_CPU1_SB_DQ<21>
J 0
(-3340 3135);
DISPLAY 0.659574 (-3340 3135);
PAINT MONO (-3340 3135);
DISPLAY INVISIBLE (-3340 3135);
FORCEPROP 1 LASTPIN (-3350 3125) BN 21
J 0
(-3362 3133);
DISPLAY 0.489362 (-3362 3133);
PAINT GREEN (-3362 3133);
FORCEPROP 2 LAST CDS_LIB mstr_standard
J 0
(-3300 3125);
DISPLAY 0.723404 (-3300 3125);
PAINT MONO (-3300 3125);
DISPLAY INVISIBLE (-3300 3125);
FORCEPROP 1 LAST BODY_TYPE PLUMBING
J 0
(-3300 3175);
DISPLAY 0.872340 (-3300 3175);
PAINT GREEN (-3300 3175);
DISPLAY INVISIBLE (-3300 3175);
FORCEPROP 1 LAST HDL_TAP TRUE
J 0
(-2975 3000);
DISPLAY 0.872340 (-2975 3000);
DISPLAY INVISIBLE (-2975 3000);
FORCEPROP 1 LAST PATH I224
J 0
(-3302 3125);
DISPLAY 0.872340 (-3302 3125);
PAINT GREEN (-3302 3125);
DISPLAY INVISIBLE (-3302 3125);
FORCEADD TAP..1
(-3300 3075);
FORCEPROP 3 LASTPIN (-3350 3075) SIG_NAME M_A_CPU1_SB_DQ<22>
J 0
(-3340 3085);
DISPLAY 0.659574 (-3340 3085);
PAINT MONO (-3340 3085);
DISPLAY INVISIBLE (-3340 3085);
FORCEPROP 1 LASTPIN (-3350 3075) BN 22
J 0
(-3362 3083);
DISPLAY 0.489362 (-3362 3083);
PAINT GREEN (-3362 3083);
FORCEPROP 2 LAST CDS_LIB mstr_standard
J 0
(-3300 3075);
DISPLAY 0.723404 (-3300 3075);
PAINT MONO (-3300 3075);
DISPLAY INVISIBLE (-3300 3075);
FORCEPROP 1 LAST BODY_TYPE PLUMBING
J 0
(-3300 3125);
DISPLAY 0.872340 (-3300 3125);
PAINT GREEN (-3300 3125);
DISPLAY INVISIBLE (-3300 3125);
FORCEPROP 1 LAST HDL_TAP TRUE
J 0
(-2975 2950);
DISPLAY 0.872340 (-2975 2950);
DISPLAY INVISIBLE (-2975 2950);
FORCEPROP 1 LAST PATH I225
J 0
(-3302 3075);
DISPLAY 0.872340 (-3302 3075);
PAINT GREEN (-3302 3075);
DISPLAY INVISIBLE (-3302 3075);
FORCEADD TAP..1
(-3300 3025);
FORCEPROP 3 LASTPIN (-3350 3025) SIG_NAME M_A_CPU1_SB_DQ<23>
J 0
(-3340 3035);
DISPLAY 0.659574 (-3340 3035);
PAINT MONO (-3340 3035);
DISPLAY INVISIBLE (-3340 3035);
FORCEPROP 1 LASTPIN (-3350 3025) BN 23
J 0
(-3362 3033);
DISPLAY 0.489362 (-3362 3033);
PAINT GREEN (-3362 3033);
FORCEPROP 2 LAST CDS_LIB mstr_standard
J 0
(-3300 3025);
DISPLAY 0.723404 (-3300 3025);
PAINT MONO (-3300 3025);
DISPLAY INVISIBLE (-3300 3025);
FORCEPROP 1 LAST BODY_TYPE PLUMBING
J 0
(-3300 3075);
DISPLAY 0.872340 (-3300 3075);
PAINT GREEN (-3300 3075);
DISPLAY INVISIBLE (-3300 3075);
FORCEPROP 1 LAST HDL_TAP TRUE
J 0
(-2975 2900);
DISPLAY 0.872340 (-2975 2900);
DISPLAY INVISIBLE (-2975 2900);
FORCEPROP 1 LAST PATH I226
J 0
(-3302 3025);
DISPLAY 0.872340 (-3302 3025);
PAINT GREEN (-3302 3025);
DISPLAY INVISIBLE (-3302 3025);
FORCEADD TAP..1
(-3300 2925);
FORCEPROP 3 LASTPIN (-3350 2925) SIG_NAME M_A_CPU1_SB_DQ<24>
J 0
(-3340 2935);
DISPLAY 0.659574 (-3340 2935);
PAINT MONO (-3340 2935);
DISPLAY INVISIBLE (-3340 2935);
FORCEPROP 1 LASTPIN (-3350 2925) BN 24
J 0
(-3362 2933);
DISPLAY 0.489362 (-3362 2933);
PAINT GREEN (-3362 2933);
FORCEPROP 2 LAST CDS_LIB mstr_standard
J 0
(-3300 2925);
DISPLAY 0.723404 (-3300 2925);
PAINT MONO (-3300 2925);
DISPLAY INVISIBLE (-3300 2925);
FORCEPROP 1 LAST BODY_TYPE PLUMBING
J 0
(-3300 2975);
DISPLAY 0.872340 (-3300 2975);
PAINT GREEN (-3300 2975);
DISPLAY INVISIBLE (-3300 2975);
FORCEPROP 1 LAST HDL_TAP TRUE
J 0
(-2975 2800);
DISPLAY 0.872340 (-2975 2800);
DISPLAY INVISIBLE (-2975 2800);
FORCEPROP 1 LAST PATH I227
J 0
(-3302 2925);
DISPLAY 0.872340 (-3302 2925);
PAINT GREEN (-3302 2925);
DISPLAY INVISIBLE (-3302 2925);
FORCEADD TAP..1
(-3300 2875);
FORCEPROP 3 LASTPIN (-3350 2875) SIG_NAME M_A_CPU1_SB_DQ<25>
J 0
(-3340 2885);
DISPLAY 0.659574 (-3340 2885);
PAINT MONO (-3340 2885);
DISPLAY INVISIBLE (-3340 2885);
FORCEPROP 1 LASTPIN (-3350 2875) BN 25
J 0
(-3362 2883);
DISPLAY 0.489362 (-3362 2883);
PAINT GREEN (-3362 2883);
FORCEPROP 2 LAST CDS_LIB mstr_standard
J 0
(-3300 2875);
DISPLAY 0.723404 (-3300 2875);
PAINT MONO (-3300 2875);
DISPLAY INVISIBLE (-3300 2875);
FORCEPROP 1 LAST BODY_TYPE PLUMBING
J 0
(-3300 2925);
DISPLAY 0.872340 (-3300 2925);
PAINT GREEN (-3300 2925);
DISPLAY INVISIBLE (-3300 2925);
FORCEPROP 1 LAST HDL_TAP TRUE
J 0
(-2975 2750);
DISPLAY 0.872340 (-2975 2750);
DISPLAY INVISIBLE (-2975 2750);
FORCEPROP 1 LAST PATH I228
J 0
(-3302 2875);
DISPLAY 0.872340 (-3302 2875);
PAINT GREEN (-3302 2875);
DISPLAY INVISIBLE (-3302 2875);
FORCEADD TAP..1
(-3300 2825);
FORCEPROP 3 LASTPIN (-3350 2825) SIG_NAME M_A_CPU1_SB_DQ<26>
J 0
(-3340 2835);
DISPLAY 0.659574 (-3340 2835);
PAINT MONO (-3340 2835);
DISPLAY INVISIBLE (-3340 2835);
FORCEPROP 1 LASTPIN (-3350 2825) BN 26
J 0
(-3362 2833);
DISPLAY 0.489362 (-3362 2833);
PAINT GREEN (-3362 2833);
FORCEPROP 2 LAST CDS_LIB mstr_standard
J 0
(-3300 2825);
DISPLAY 0.723404 (-3300 2825);
PAINT MONO (-3300 2825);
DISPLAY INVISIBLE (-3300 2825);
FORCEPROP 1 LAST BODY_TYPE PLUMBING
J 0
(-3300 2875);
DISPLAY 0.872340 (-3300 2875);
PAINT GREEN (-3300 2875);
DISPLAY INVISIBLE (-3300 2875);
FORCEPROP 1 LAST HDL_TAP TRUE
J 0
(-2975 2700);
DISPLAY 0.872340 (-2975 2700);
DISPLAY INVISIBLE (-2975 2700);
FORCEPROP 1 LAST PATH I229
J 0
(-3302 2825);
DISPLAY 0.872340 (-3302 2825);
PAINT GREEN (-3302 2825);
DISPLAY INVISIBLE (-3302 2825);
FORCEADD TAP..1
(-3300 2775);
FORCEPROP 3 LASTPIN (-3350 2775) SIG_NAME M_A_CPU1_SB_DQ<27>
J 0
(-3340 2785);
DISPLAY 0.659574 (-3340 2785);
PAINT MONO (-3340 2785);
DISPLAY INVISIBLE (-3340 2785);
FORCEPROP 1 LASTPIN (-3350 2775) BN 27
J 0
(-3362 2783);
DISPLAY 0.489362 (-3362 2783);
PAINT GREEN (-3362 2783);
FORCEPROP 2 LAST CDS_LIB mstr_standard
J 0
(-3300 2775);
DISPLAY 0.723404 (-3300 2775);
PAINT MONO (-3300 2775);
DISPLAY INVISIBLE (-3300 2775);
FORCEPROP 1 LAST BODY_TYPE PLUMBING
J 0
(-3300 2825);
DISPLAY 0.872340 (-3300 2825);
PAINT GREEN (-3300 2825);
DISPLAY INVISIBLE (-3300 2825);
FORCEPROP 1 LAST HDL_TAP TRUE
J 0
(-2975 2650);
DISPLAY 0.872340 (-2975 2650);
DISPLAY INVISIBLE (-2975 2650);
FORCEPROP 1 LAST PATH I230
J 0
(-3302 2775);
DISPLAY 0.872340 (-3302 2775);
PAINT GREEN (-3302 2775);
DISPLAY INVISIBLE (-3302 2775);
FORCEADD TAP..1
(-3300 2725);
FORCEPROP 3 LASTPIN (-3350 2725) SIG_NAME M_A_CPU1_SB_DQ<28>
J 0
(-3340 2735);
DISPLAY 0.659574 (-3340 2735);
PAINT MONO (-3340 2735);
DISPLAY INVISIBLE (-3340 2735);
FORCEPROP 1 LASTPIN (-3350 2725) BN 28
J 0
(-3362 2733);
DISPLAY 0.489362 (-3362 2733);
PAINT GREEN (-3362 2733);
FORCEPROP 2 LAST CDS_LIB mstr_standard
J 0
(-3300 2725);
DISPLAY 0.723404 (-3300 2725);
PAINT MONO (-3300 2725);
DISPLAY INVISIBLE (-3300 2725);
FORCEPROP 1 LAST BODY_TYPE PLUMBING
J 0
(-3300 2775);
DISPLAY 0.872340 (-3300 2775);
PAINT GREEN (-3300 2775);
DISPLAY INVISIBLE (-3300 2775);
FORCEPROP 1 LAST HDL_TAP TRUE
J 0
(-2975 2600);
DISPLAY 0.872340 (-2975 2600);
DISPLAY INVISIBLE (-2975 2600);
FORCEPROP 1 LAST PATH I231
J 0
(-3302 2725);
DISPLAY 0.872340 (-3302 2725);
PAINT GREEN (-3302 2725);
DISPLAY INVISIBLE (-3302 2725);
FORCEADD TAP..1
(-3300 2675);
FORCEPROP 3 LASTPIN (-3350 2675) SIG_NAME M_A_CPU1_SB_DQ<29>
J 0
(-3340 2685);
DISPLAY 0.659574 (-3340 2685);
PAINT MONO (-3340 2685);
DISPLAY INVISIBLE (-3340 2685);
FORCEPROP 1 LASTPIN (-3350 2675) BN 29
J 0
(-3362 2683);
DISPLAY 0.489362 (-3362 2683);
PAINT GREEN (-3362 2683);
FORCEPROP 2 LAST CDS_LIB mstr_standard
J 0
(-3300 2675);
DISPLAY 0.723404 (-3300 2675);
PAINT MONO (-3300 2675);
DISPLAY INVISIBLE (-3300 2675);
FORCEPROP 1 LAST BODY_TYPE PLUMBING
J 0
(-3300 2725);
DISPLAY 0.872340 (-3300 2725);
PAINT GREEN (-3300 2725);
DISPLAY INVISIBLE (-3300 2725);
FORCEPROP 1 LAST HDL_TAP TRUE
J 0
(-2975 2550);
DISPLAY 0.872340 (-2975 2550);
DISPLAY INVISIBLE (-2975 2550);
FORCEPROP 1 LAST PATH I232
J 0
(-3302 2675);
DISPLAY 0.872340 (-3302 2675);
PAINT GREEN (-3302 2675);
DISPLAY INVISIBLE (-3302 2675);
FORCEADD TAP..1
(-3300 2625);
FORCEPROP 3 LASTPIN (-3350 2625) SIG_NAME M_A_CPU1_SB_DQ<30>
J 0
(-3340 2635);
DISPLAY 0.659574 (-3340 2635);
PAINT MONO (-3340 2635);
DISPLAY INVISIBLE (-3340 2635);
FORCEPROP 1 LASTPIN (-3350 2625) BN 30
J 0
(-3362 2633);
DISPLAY 0.489362 (-3362 2633);
PAINT GREEN (-3362 2633);
FORCEPROP 2 LAST CDS_LIB mstr_standard
J 0
(-3300 2625);
DISPLAY 0.723404 (-3300 2625);
PAINT MONO (-3300 2625);
DISPLAY INVISIBLE (-3300 2625);
FORCEPROP 1 LAST BODY_TYPE PLUMBING
J 0
(-3300 2675);
DISPLAY 0.872340 (-3300 2675);
PAINT GREEN (-3300 2675);
DISPLAY INVISIBLE (-3300 2675);
FORCEPROP 1 LAST HDL_TAP TRUE
J 0
(-2975 2500);
DISPLAY 0.872340 (-2975 2500);
DISPLAY INVISIBLE (-2975 2500);
FORCEPROP 1 LAST PATH I233
J 0
(-3302 2625);
DISPLAY 0.872340 (-3302 2625);
PAINT GREEN (-3302 2625);
DISPLAY INVISIBLE (-3302 2625);
FORCEADD TAP..1
(-3300 2575);
FORCEPROP 3 LASTPIN (-3350 2575) SIG_NAME M_A_CPU1_SB_DQ<31>
J 0
(-3340 2585);
DISPLAY 0.659574 (-3340 2585);
PAINT MONO (-3340 2585);
DISPLAY INVISIBLE (-3340 2585);
FORCEPROP 1 LASTPIN (-3350 2575) BN 31
J 0
(-3362 2583);
DISPLAY 0.489362 (-3362 2583);
PAINT GREEN (-3362 2583);
FORCEPROP 2 LAST CDS_LIB mstr_standard
J 0
(-3300 2575);
DISPLAY 0.723404 (-3300 2575);
PAINT MONO (-3300 2575);
DISPLAY INVISIBLE (-3300 2575);
FORCEPROP 1 LAST BODY_TYPE PLUMBING
J 0
(-3300 2625);
DISPLAY 0.872340 (-3300 2625);
PAINT GREEN (-3300 2625);
DISPLAY INVISIBLE (-3300 2625);
FORCEPROP 1 LAST HDL_TAP TRUE
J 0
(-2975 2450);
DISPLAY 0.872340 (-2975 2450);
DISPLAY INVISIBLE (-2975 2450);
FORCEPROP 1 LAST PATH I234
J 0
(-3302 2575);
DISPLAY 0.872340 (-3302 2575);
PAINT GREEN (-3302 2575);
DISPLAY INVISIBLE (-3302 2575);
FORCEADD TAP..1
(-3300 2475);
FORCEPROP 3 LASTPIN (-3350 2475) SIG_NAME M_A_CPU1_SA_CB<0>
J 0
(-3340 2485);
DISPLAY 0.659574 (-3340 2485);
PAINT MONO (-3340 2485);
DISPLAY INVISIBLE (-3340 2485);
FORCEPROP 1 LASTPIN (-3350 2475) BN 0
J 0
(-3362 2483);
DISPLAY 0.489362 (-3362 2483);
PAINT GREEN (-3362 2483);
FORCEPROP 2 LAST CDS_LIB mstr_standard
J 2
(-3300 2475);
DISPLAY 0.723404 (-3300 2475);
PAINT MONO (-3300 2475);
DISPLAY INVISIBLE (-3300 2475);
FORCEPROP 1 LAST BODY_TYPE PLUMBING
J 0
(-3300 2525);
DISPLAY 0.872340 (-3300 2525);
PAINT GREEN (-3300 2525);
DISPLAY INVISIBLE (-3300 2525);
FORCEPROP 1 LAST HDL_TAP TRUE
J 0
(-2975 2350);
DISPLAY 0.872340 (-2975 2350);
DISPLAY INVISIBLE (-2975 2350);
FORCEPROP 1 LAST PATH I235
J 0
(-3302 2475);
DISPLAY 0.872340 (-3302 2475);
PAINT GREEN (-3302 2475);
DISPLAY INVISIBLE (-3302 2475);
FORCEADD TAP..1
(-3300 2375);
FORCEPROP 3 LASTPIN (-3350 2375) SIG_NAME M_A_CPU1_SA_CB<2>
J 0
(-3340 2385);
DISPLAY 0.659574 (-3340 2385);
PAINT MONO (-3340 2385);
DISPLAY INVISIBLE (-3340 2385);
FORCEPROP 1 LASTPIN (-3350 2375) BN 2
J 0
(-3362 2383);
DISPLAY 0.489362 (-3362 2383);
PAINT GREEN (-3362 2383);
FORCEPROP 2 LAST CDS_LIB mstr_standard
J 2
(-3300 2375);
DISPLAY 0.723404 (-3300 2375);
PAINT MONO (-3300 2375);
DISPLAY INVISIBLE (-3300 2375);
FORCEPROP 1 LAST BODY_TYPE PLUMBING
J 0
(-3300 2425);
DISPLAY 0.872340 (-3300 2425);
PAINT GREEN (-3300 2425);
DISPLAY INVISIBLE (-3300 2425);
FORCEPROP 1 LAST HDL_TAP TRUE
J 0
(-2975 2250);
DISPLAY 0.872340 (-2975 2250);
DISPLAY INVISIBLE (-2975 2250);
FORCEPROP 1 LAST PATH I236
J 0
(-3302 2375);
DISPLAY 0.872340 (-3302 2375);
PAINT GREEN (-3302 2375);
DISPLAY INVISIBLE (-3302 2375);
FORCEADD TAP..1
(-3300 2425);
FORCEPROP 3 LASTPIN (-3350 2425) SIG_NAME M_A_CPU1_SA_CB<1>
J 0
(-3340 2435);
DISPLAY 0.659574 (-3340 2435);
PAINT MONO (-3340 2435);
DISPLAY INVISIBLE (-3340 2435);
FORCEPROP 1 LASTPIN (-3350 2425) BN 1
J 0
(-3362 2433);
DISPLAY 0.489362 (-3362 2433);
PAINT GREEN (-3362 2433);
FORCEPROP 2 LAST CDS_LIB mstr_standard
J 2
(-3300 2425);
DISPLAY 0.723404 (-3300 2425);
PAINT MONO (-3300 2425);
DISPLAY INVISIBLE (-3300 2425);
FORCEPROP 1 LAST BODY_TYPE PLUMBING
J 0
(-3300 2475);
DISPLAY 0.872340 (-3300 2475);
PAINT GREEN (-3300 2475);
DISPLAY INVISIBLE (-3300 2475);
FORCEPROP 1 LAST HDL_TAP TRUE
J 0
(-2975 2300);
DISPLAY 0.872340 (-2975 2300);
DISPLAY INVISIBLE (-2975 2300);
FORCEPROP 1 LAST PATH I237
J 0
(-3302 2425);
DISPLAY 0.872340 (-3302 2425);
PAINT GREEN (-3302 2425);
DISPLAY INVISIBLE (-3302 2425);
FORCEADD TAP..1
(-3300 2325);
FORCEPROP 3 LASTPIN (-3350 2325) SIG_NAME M_A_CPU1_SA_CB<3>
J 0
(-3340 2335);
DISPLAY 0.659574 (-3340 2335);
PAINT MONO (-3340 2335);
DISPLAY INVISIBLE (-3340 2335);
FORCEPROP 1 LASTPIN (-3350 2325) BN 3
J 0
(-3362 2333);
DISPLAY 0.489362 (-3362 2333);
PAINT GREEN (-3362 2333);
FORCEPROP 2 LAST CDS_LIB mstr_standard
J 2
(-3300 2325);
DISPLAY 0.723404 (-3300 2325);
PAINT MONO (-3300 2325);
DISPLAY INVISIBLE (-3300 2325);
FORCEPROP 1 LAST BODY_TYPE PLUMBING
J 0
(-3300 2375);
DISPLAY 0.872340 (-3300 2375);
PAINT GREEN (-3300 2375);
DISPLAY INVISIBLE (-3300 2375);
FORCEPROP 1 LAST HDL_TAP TRUE
J 0
(-2975 2200);
DISPLAY 0.872340 (-2975 2200);
DISPLAY INVISIBLE (-2975 2200);
FORCEPROP 1 LAST PATH I238
J 0
(-3302 2325);
DISPLAY 0.872340 (-3302 2325);
PAINT GREEN (-3302 2325);
DISPLAY INVISIBLE (-3302 2325);
FORCEADD TAP..1
(-3300 2275);
FORCEPROP 3 LASTPIN (-3350 2275) SIG_NAME M_A_CPU1_SA_CB<4>
J 0
(-3340 2285);
DISPLAY 0.659574 (-3340 2285);
PAINT MONO (-3340 2285);
DISPLAY INVISIBLE (-3340 2285);
FORCEPROP 1 LASTPIN (-3350 2275) BN 4
J 0
(-3362 2283);
DISPLAY 0.489362 (-3362 2283);
PAINT GREEN (-3362 2283);
FORCEPROP 2 LAST CDS_LIB mstr_standard
J 2
(-3300 2275);
DISPLAY 0.723404 (-3300 2275);
PAINT MONO (-3300 2275);
DISPLAY INVISIBLE (-3300 2275);
FORCEPROP 1 LAST BODY_TYPE PLUMBING
J 0
(-3300 2325);
DISPLAY 0.872340 (-3300 2325);
PAINT GREEN (-3300 2325);
DISPLAY INVISIBLE (-3300 2325);
FORCEPROP 1 LAST HDL_TAP TRUE
J 0
(-2975 2150);
DISPLAY 0.872340 (-2975 2150);
DISPLAY INVISIBLE (-2975 2150);
FORCEPROP 1 LAST PATH I239
J 0
(-3302 2275);
DISPLAY 0.872340 (-3302 2275);
PAINT GREEN (-3302 2275);
DISPLAY INVISIBLE (-3302 2275);
FORCEADD TAP..1
(-3300 2225);
FORCEPROP 3 LASTPIN (-3350 2225) SIG_NAME M_A_CPU1_SA_CB<5>
J 0
(-3340 2235);
DISPLAY 0.659574 (-3340 2235);
PAINT MONO (-3340 2235);
DISPLAY INVISIBLE (-3340 2235);
FORCEPROP 1 LASTPIN (-3350 2225) BN 5
J 0
(-3362 2233);
DISPLAY 0.489362 (-3362 2233);
PAINT GREEN (-3362 2233);
FORCEPROP 2 LAST CDS_LIB mstr_standard
J 2
(-3300 2225);
DISPLAY 0.723404 (-3300 2225);
PAINT MONO (-3300 2225);
DISPLAY INVISIBLE (-3300 2225);
FORCEPROP 1 LAST BODY_TYPE PLUMBING
J 0
(-3300 2275);
DISPLAY 0.872340 (-3300 2275);
PAINT GREEN (-3300 2275);
DISPLAY INVISIBLE (-3300 2275);
FORCEPROP 1 LAST HDL_TAP TRUE
J 0
(-2975 2100);
DISPLAY 0.872340 (-2975 2100);
DISPLAY INVISIBLE (-2975 2100);
FORCEPROP 1 LAST PATH I240
J 0
(-3302 2225);
DISPLAY 0.872340 (-3302 2225);
PAINT GREEN (-3302 2225);
DISPLAY INVISIBLE (-3302 2225);
FORCEADD TAP..1
(-3300 2175);
FORCEPROP 3 LASTPIN (-3350 2175) SIG_NAME M_A_CPU1_SA_CB<6>
J 0
(-3340 2185);
DISPLAY 0.659574 (-3340 2185);
PAINT MONO (-3340 2185);
DISPLAY INVISIBLE (-3340 2185);
FORCEPROP 1 LASTPIN (-3350 2175) BN 6
J 0
(-3362 2183);
DISPLAY 0.489362 (-3362 2183);
PAINT GREEN (-3362 2183);
FORCEPROP 2 LAST CDS_LIB mstr_standard
J 2
(-3300 2175);
DISPLAY 0.723404 (-3300 2175);
PAINT MONO (-3300 2175);
DISPLAY INVISIBLE (-3300 2175);
FORCEPROP 1 LAST BODY_TYPE PLUMBING
J 0
(-3300 2225);
DISPLAY 0.872340 (-3300 2225);
PAINT GREEN (-3300 2225);
DISPLAY INVISIBLE (-3300 2225);
FORCEPROP 1 LAST HDL_TAP TRUE
J 0
(-2975 2050);
DISPLAY 0.872340 (-2975 2050);
DISPLAY INVISIBLE (-2975 2050);
FORCEPROP 1 LAST PATH I241
J 0
(-3302 2175);
DISPLAY 0.872340 (-3302 2175);
PAINT GREEN (-3302 2175);
DISPLAY INVISIBLE (-3302 2175);
FORCEADD TAP..1
(-3300 2125);
FORCEPROP 3 LASTPIN (-3350 2125) SIG_NAME M_A_CPU1_SA_CB<7>
J 0
(-3340 2135);
DISPLAY 0.659574 (-3340 2135);
PAINT MONO (-3340 2135);
DISPLAY INVISIBLE (-3340 2135);
FORCEPROP 1 LASTPIN (-3350 2125) BN 7
J 0
(-3362 2133);
DISPLAY 0.489362 (-3362 2133);
PAINT GREEN (-3362 2133);
FORCEPROP 2 LAST CDS_LIB mstr_standard
J 2
(-3300 2125);
DISPLAY 0.723404 (-3300 2125);
PAINT MONO (-3300 2125);
DISPLAY INVISIBLE (-3300 2125);
FORCEPROP 1 LAST BODY_TYPE PLUMBING
J 0
(-3300 2175);
DISPLAY 0.872340 (-3300 2175);
PAINT GREEN (-3300 2175);
DISPLAY INVISIBLE (-3300 2175);
FORCEPROP 1 LAST HDL_TAP TRUE
J 0
(-2975 2000);
DISPLAY 0.872340 (-2975 2000);
DISPLAY INVISIBLE (-2975 2000);
FORCEPROP 1 LAST PATH I242
J 0
(-3302 2125);
DISPLAY 0.872340 (-3302 2125);
PAINT GREEN (-3302 2125);
DISPLAY INVISIBLE (-3302 2125);
FORCEADD OFFPAGE..6
R 2
(-2700 2075);
FORCEPROP 2 LAST $XR0 97 
J 0
(-2486 2075);
DISPLAY 0.638298 (-2486 2075);
PAINT MONO (-2486 2075);
FORCEPROP 2 LAST PATH I243
J 0
(-2475 2125);
DISPLAY 1.021277 (-2475 2125);
DISPLAY INVISIBLE (-2475 2125);
FORCEPROP 1 LAST COMMENT_BODY TRUE
J 2
(-2800 2000);
DISPLAY 0.872340 (-2800 2000);
PAINT GREEN (-2800 2000);
DISPLAY INVISIBLE (-2800 2000);
FORCEPROP 1 LAST OFFPAGE TRUE
J 2
(-3025 1950);
DISPLAY 0.872340 (-3025 1950);
PAINT GREEN (-3025 1950);
DISPLAY INVISIBLE (-3025 1950);
FORCEPROP 2 LAST CDS_LIB mstr_standard
J 2
(-2700 2075);
DISPLAY 0.723404 (-2700 2075);
PAINT MONO (-2700 2075);
DISPLAY INVISIBLE (-2700 2075);
FORCEADD TAP..1
(-3300 2025);
FORCEPROP 3 LASTPIN (-3350 2025) SIG_NAME M_A_CPU1_SB_CB<0>
J 0
(-3340 2035);
DISPLAY 0.659574 (-3340 2035);
PAINT MONO (-3340 2035);
DISPLAY INVISIBLE (-3340 2035);
FORCEPROP 1 LASTPIN (-3350 2025) BN 0
J 0
(-3362 2033);
DISPLAY 0.489362 (-3362 2033);
PAINT GREEN (-3362 2033);
FORCEPROP 2 LAST CDS_LIB mstr_standard
J 2
(-3300 2025);
DISPLAY 0.723404 (-3300 2025);
PAINT MONO (-3300 2025);
DISPLAY INVISIBLE (-3300 2025);
FORCEPROP 1 LAST BODY_TYPE PLUMBING
J 0
(-3300 2075);
DISPLAY 0.872340 (-3300 2075);
PAINT GREEN (-3300 2075);
DISPLAY INVISIBLE (-3300 2075);
FORCEPROP 1 LAST HDL_TAP TRUE
J 0
(-2975 1900);
DISPLAY 0.872340 (-2975 1900);
DISPLAY INVISIBLE (-2975 1900);
FORCEPROP 1 LAST PATH I244
J 0
(-3302 2025);
DISPLAY 0.872340 (-3302 2025);
PAINT GREEN (-3302 2025);
DISPLAY INVISIBLE (-3302 2025);
FORCEADD TAP..1
(-3300 1975);
FORCEPROP 3 LASTPIN (-3350 1975) SIG_NAME M_A_CPU1_SB_CB<1>
J 0
(-3340 1985);
DISPLAY 0.659574 (-3340 1985);
PAINT MONO (-3340 1985);
DISPLAY INVISIBLE (-3340 1985);
FORCEPROP 1 LASTPIN (-3350 1975) BN 1
J 0
(-3362 1983);
DISPLAY 0.489362 (-3362 1983);
PAINT GREEN (-3362 1983);
FORCEPROP 2 LAST CDS_LIB mstr_standard
J 2
(-3300 1975);
DISPLAY 0.723404 (-3300 1975);
PAINT MONO (-3300 1975);
DISPLAY INVISIBLE (-3300 1975);
FORCEPROP 1 LAST BODY_TYPE PLUMBING
J 0
(-3300 2025);
DISPLAY 0.872340 (-3300 2025);
PAINT GREEN (-3300 2025);
DISPLAY INVISIBLE (-3300 2025);
FORCEPROP 1 LAST HDL_TAP TRUE
J 0
(-2975 1850);
DISPLAY 0.872340 (-2975 1850);
DISPLAY INVISIBLE (-2975 1850);
FORCEPROP 1 LAST PATH I245
J 0
(-3302 1975);
DISPLAY 0.872340 (-3302 1975);
PAINT GREEN (-3302 1975);
DISPLAY INVISIBLE (-3302 1975);
FORCEADD TAP..1
(-3300 1925);
FORCEPROP 3 LASTPIN (-3350 1925) SIG_NAME M_A_CPU1_SB_CB<2>
J 0
(-3340 1935);
DISPLAY 0.659574 (-3340 1935);
PAINT MONO (-3340 1935);
DISPLAY INVISIBLE (-3340 1935);
FORCEPROP 1 LASTPIN (-3350 1925) BN 2
J 0
(-3362 1933);
DISPLAY 0.489362 (-3362 1933);
PAINT GREEN (-3362 1933);
FORCEPROP 2 LAST CDS_LIB mstr_standard
J 2
(-3300 1925);
DISPLAY 0.723404 (-3300 1925);
PAINT MONO (-3300 1925);
DISPLAY INVISIBLE (-3300 1925);
FORCEPROP 1 LAST BODY_TYPE PLUMBING
J 0
(-3300 1975);
DISPLAY 0.872340 (-3300 1975);
PAINT GREEN (-3300 1975);
DISPLAY INVISIBLE (-3300 1975);
FORCEPROP 1 LAST HDL_TAP TRUE
J 0
(-2975 1800);
DISPLAY 0.872340 (-2975 1800);
DISPLAY INVISIBLE (-2975 1800);
FORCEPROP 1 LAST PATH I246
J 0
(-3302 1925);
DISPLAY 0.872340 (-3302 1925);
PAINT GREEN (-3302 1925);
DISPLAY INVISIBLE (-3302 1925);
FORCEADD TAP..1
(-3300 1825);
FORCEPROP 3 LASTPIN (-3350 1825) SIG_NAME M_A_CPU1_SB_CB<4>
J 0
(-3340 1835);
DISPLAY 0.659574 (-3340 1835);
PAINT MONO (-3340 1835);
DISPLAY INVISIBLE (-3340 1835);
FORCEPROP 1 LASTPIN (-3350 1825) BN 4
J 0
(-3362 1833);
DISPLAY 0.489362 (-3362 1833);
PAINT GREEN (-3362 1833);
FORCEPROP 2 LAST CDS_LIB mstr_standard
J 2
(-3300 1825);
DISPLAY 0.723404 (-3300 1825);
PAINT MONO (-3300 1825);
DISPLAY INVISIBLE (-3300 1825);
FORCEPROP 1 LAST BODY_TYPE PLUMBING
J 0
(-3300 1875);
DISPLAY 0.872340 (-3300 1875);
PAINT GREEN (-3300 1875);
DISPLAY INVISIBLE (-3300 1875);
FORCEPROP 1 LAST HDL_TAP TRUE
J 0
(-2975 1700);
DISPLAY 0.872340 (-2975 1700);
DISPLAY INVISIBLE (-2975 1700);
FORCEPROP 1 LAST PATH I247
J 0
(-3302 1825);
DISPLAY 0.872340 (-3302 1825);
PAINT GREEN (-3302 1825);
DISPLAY INVISIBLE (-3302 1825);
FORCEADD TAP..1
(-3300 1875);
FORCEPROP 3 LASTPIN (-3350 1875) SIG_NAME M_A_CPU1_SB_CB<3>
J 0
(-3340 1885);
DISPLAY 0.659574 (-3340 1885);
PAINT MONO (-3340 1885);
DISPLAY INVISIBLE (-3340 1885);
FORCEPROP 1 LASTPIN (-3350 1875) BN 3
J 0
(-3362 1883);
DISPLAY 0.489362 (-3362 1883);
PAINT GREEN (-3362 1883);
FORCEPROP 2 LAST CDS_LIB mstr_standard
J 2
(-3300 1875);
DISPLAY 0.723404 (-3300 1875);
PAINT MONO (-3300 1875);
DISPLAY INVISIBLE (-3300 1875);
FORCEPROP 1 LAST BODY_TYPE PLUMBING
J 0
(-3300 1925);
DISPLAY 0.872340 (-3300 1925);
PAINT GREEN (-3300 1925);
DISPLAY INVISIBLE (-3300 1925);
FORCEPROP 1 LAST HDL_TAP TRUE
J 0
(-2975 1750);
DISPLAY 0.872340 (-2975 1750);
DISPLAY INVISIBLE (-2975 1750);
FORCEPROP 1 LAST PATH I248
J 0
(-3302 1875);
DISPLAY 0.872340 (-3302 1875);
PAINT GREEN (-3302 1875);
DISPLAY INVISIBLE (-3302 1875);
FORCEADD TAP..1
(-3300 1775);
FORCEPROP 3 LASTPIN (-3350 1775) SIG_NAME M_A_CPU1_SB_CB<5>
J 0
(-3340 1785);
DISPLAY 0.659574 (-3340 1785);
PAINT MONO (-3340 1785);
DISPLAY INVISIBLE (-3340 1785);
FORCEPROP 1 LASTPIN (-3350 1775) BN 5
J 0
(-3362 1783);
DISPLAY 0.489362 (-3362 1783);
PAINT GREEN (-3362 1783);
FORCEPROP 2 LAST CDS_LIB mstr_standard
J 2
(-3300 1775);
DISPLAY 0.723404 (-3300 1775);
PAINT MONO (-3300 1775);
DISPLAY INVISIBLE (-3300 1775);
FORCEPROP 1 LAST BODY_TYPE PLUMBING
J 0
(-3300 1825);
DISPLAY 0.872340 (-3300 1825);
PAINT GREEN (-3300 1825);
DISPLAY INVISIBLE (-3300 1825);
FORCEPROP 1 LAST HDL_TAP TRUE
J 0
(-2975 1650);
DISPLAY 0.872340 (-2975 1650);
DISPLAY INVISIBLE (-2975 1650);
FORCEPROP 1 LAST PATH I249
J 0
(-3302 1775);
DISPLAY 0.872340 (-3302 1775);
PAINT GREEN (-3302 1775);
DISPLAY INVISIBLE (-3302 1775);
FORCEADD TAP..1
(-3300 1675);
FORCEPROP 3 LASTPIN (-3350 1675) SIG_NAME M_A_CPU1_SB_CB<7>
J 0
(-3340 1685);
DISPLAY 0.659574 (-3340 1685);
PAINT MONO (-3340 1685);
DISPLAY INVISIBLE (-3340 1685);
FORCEPROP 1 LASTPIN (-3350 1675) BN 7
J 0
(-3362 1683);
DISPLAY 0.489362 (-3362 1683);
PAINT GREEN (-3362 1683);
FORCEPROP 2 LAST CDS_LIB mstr_standard
J 2
(-3300 1675);
DISPLAY 0.723404 (-3300 1675);
PAINT MONO (-3300 1675);
DISPLAY INVISIBLE (-3300 1675);
FORCEPROP 1 LAST BODY_TYPE PLUMBING
J 0
(-3300 1725);
DISPLAY 0.872340 (-3300 1725);
PAINT GREEN (-3300 1725);
DISPLAY INVISIBLE (-3300 1725);
FORCEPROP 1 LAST HDL_TAP TRUE
J 0
(-2975 1550);
DISPLAY 0.872340 (-2975 1550);
DISPLAY INVISIBLE (-2975 1550);
FORCEPROP 1 LAST PATH I250
J 0
(-3302 1675);
DISPLAY 0.872340 (-3302 1675);
PAINT GREEN (-3302 1675);
DISPLAY INVISIBLE (-3302 1675);
FORCEADD TAP..1
(-3300 1725);
FORCEPROP 3 LASTPIN (-3350 1725) SIG_NAME M_A_CPU1_SB_CB<6>
J 0
(-3340 1735);
DISPLAY 0.659574 (-3340 1735);
PAINT MONO (-3340 1735);
DISPLAY INVISIBLE (-3340 1735);
FORCEPROP 1 LASTPIN (-3350 1725) BN 6
J 0
(-3362 1733);
DISPLAY 0.489362 (-3362 1733);
PAINT GREEN (-3362 1733);
FORCEPROP 2 LAST CDS_LIB mstr_standard
J 2
(-3300 1725);
DISPLAY 0.723404 (-3300 1725);
PAINT MONO (-3300 1725);
DISPLAY INVISIBLE (-3300 1725);
FORCEPROP 1 LAST BODY_TYPE PLUMBING
J 0
(-3300 1775);
DISPLAY 0.872340 (-3300 1775);
PAINT GREEN (-3300 1775);
DISPLAY INVISIBLE (-3300 1775);
FORCEPROP 1 LAST HDL_TAP TRUE
J 0
(-2975 1600);
DISPLAY 0.872340 (-2975 1600);
DISPLAY INVISIBLE (-2975 1600);
FORCEPROP 1 LAST PATH I251
J 0
(-3302 1725);
DISPLAY 0.872340 (-3302 1725);
PAINT GREEN (-3302 1725);
DISPLAY INVISIBLE (-3302 1725);
FORCEADD TAP..1
R 2
(-5725 6075);
FORCEPROP 3 LASTPIN (-5675 6075) SIG_NAME M_A_CPU1_SA_DQS_DP<0>
J 0
(-5665 6085);
DISPLAY 0.659574 (-5665 6085);
PAINT MONO (-5665 6085);
DISPLAY INVISIBLE (-5665 6085);
FORCEPROP 1 LASTPIN (-5675 6075) BN 0
J 2
(-5663 6083);
DISPLAY 0.489362 (-5663 6083);
PAINT GREEN (-5663 6083);
FORCEPROP 2 LAST CDS_LIB mstr_standard
J 2
(-5725 6075);
DISPLAY 0.723404 (-5725 6075);
PAINT MONO (-5725 6075);
DISPLAY INVISIBLE (-5725 6075);
FORCEPROP 1 LAST BODY_TYPE PLUMBING
J 2
(-5725 6125);
DISPLAY 0.872340 (-5725 6125);
PAINT GREEN (-5725 6125);
DISPLAY INVISIBLE (-5725 6125);
FORCEPROP 1 LAST HDL_TAP TRUE
J 2
(-6050 5950);
DISPLAY 0.872340 (-6050 5950);
DISPLAY INVISIBLE (-6050 5950);
FORCEPROP 1 LAST PATH I252
J 2
(-5723 6075);
DISPLAY 0.872340 (-5723 6075);
PAINT GREEN (-5723 6075);
DISPLAY INVISIBLE (-5723 6075);
FORCEADD TAP..1
R 2
(-5725 5975);
FORCEPROP 3 LASTPIN (-5675 5975) SIG_NAME M_A_CPU1_SA_DQS_DP<1>
J 0
(-5665 5985);
DISPLAY 0.659574 (-5665 5985);
PAINT MONO (-5665 5985);
DISPLAY INVISIBLE (-5665 5985);
FORCEPROP 1 LASTPIN (-5675 5975) BN 1
J 2
(-5663 5983);
DISPLAY 0.489362 (-5663 5983);
PAINT GREEN (-5663 5983);
FORCEPROP 2 LAST CDS_LIB mstr_standard
J 2
(-5725 5975);
DISPLAY 0.723404 (-5725 5975);
PAINT MONO (-5725 5975);
DISPLAY INVISIBLE (-5725 5975);
FORCEPROP 1 LAST BODY_TYPE PLUMBING
J 2
(-5725 6025);
DISPLAY 0.872340 (-5725 6025);
PAINT GREEN (-5725 6025);
DISPLAY INVISIBLE (-5725 6025);
FORCEPROP 1 LAST HDL_TAP TRUE
J 2
(-6050 5850);
DISPLAY 0.872340 (-6050 5850);
DISPLAY INVISIBLE (-6050 5850);
FORCEPROP 1 LAST PATH I253
J 2
(-5723 5975);
DISPLAY 0.872340 (-5723 5975);
PAINT GREEN (-5723 5975);
DISPLAY INVISIBLE (-5723 5975);
FORCEADD TAP..1
R 2
(-5725 5875);
FORCEPROP 3 LASTPIN (-5675 5875) SIG_NAME M_A_CPU1_SA_DQS_DP<2>
J 0
(-5665 5885);
DISPLAY 0.659574 (-5665 5885);
PAINT MONO (-5665 5885);
DISPLAY INVISIBLE (-5665 5885);
FORCEPROP 1 LASTPIN (-5675 5875) BN 2
J 2
(-5663 5883);
DISPLAY 0.489362 (-5663 5883);
PAINT GREEN (-5663 5883);
FORCEPROP 2 LAST CDS_LIB mstr_standard
J 2
(-5725 5875);
DISPLAY 0.723404 (-5725 5875);
PAINT MONO (-5725 5875);
DISPLAY INVISIBLE (-5725 5875);
FORCEPROP 1 LAST BODY_TYPE PLUMBING
J 2
(-5725 5925);
DISPLAY 0.872340 (-5725 5925);
PAINT GREEN (-5725 5925);
DISPLAY INVISIBLE (-5725 5925);
FORCEPROP 1 LAST HDL_TAP TRUE
J 2
(-6050 5750);
DISPLAY 0.872340 (-6050 5750);
DISPLAY INVISIBLE (-6050 5750);
FORCEPROP 1 LAST PATH I254
J 2
(-5723 5875);
DISPLAY 0.872340 (-5723 5875);
PAINT GREEN (-5723 5875);
DISPLAY INVISIBLE (-5723 5875);
FORCEADD TAP..1
R 2
(-5925 6025);
FORCEPROP 3 LASTPIN (-5875 6025) SIG_NAME M_A_CPU1_SA_DQS_DN<0>
J 0
(-5865 6035);
DISPLAY 0.659574 (-5865 6035);
PAINT MONO (-5865 6035);
DISPLAY INVISIBLE (-5865 6035);
FORCEPROP 1 LASTPIN (-5875 6025) BN 0
J 2
(-5863 6033);
DISPLAY 0.489362 (-5863 6033);
PAINT GREEN (-5863 6033);
FORCEPROP 2 LAST CDS_LIB mstr_standard
J 2
(-5925 6025);
DISPLAY 0.723404 (-5925 6025);
PAINT MONO (-5925 6025);
DISPLAY INVISIBLE (-5925 6025);
FORCEPROP 1 LAST BODY_TYPE PLUMBING
J 2
(-5925 6075);
DISPLAY 0.872340 (-5925 6075);
PAINT GREEN (-5925 6075);
DISPLAY INVISIBLE (-5925 6075);
FORCEPROP 1 LAST HDL_TAP TRUE
J 2
(-6250 5900);
DISPLAY 0.872340 (-6250 5900);
DISPLAY INVISIBLE (-6250 5900);
FORCEPROP 1 LAST PATH I255
J 2
(-5923 6025);
DISPLAY 0.872340 (-5923 6025);
PAINT GREEN (-5923 6025);
DISPLAY INVISIBLE (-5923 6025);
FORCEADD TAP..1
R 2
(-5925 5925);
FORCEPROP 3 LASTPIN (-5875 5925) SIG_NAME M_A_CPU1_SA_DQS_DN<1>
J 0
(-5865 5935);
DISPLAY 0.659574 (-5865 5935);
PAINT MONO (-5865 5935);
DISPLAY INVISIBLE (-5865 5935);
FORCEPROP 1 LASTPIN (-5875 5925) BN 1
J 2
(-5863 5933);
DISPLAY 0.489362 (-5863 5933);
PAINT GREEN (-5863 5933);
FORCEPROP 2 LAST CDS_LIB mstr_standard
J 2
(-5925 5925);
DISPLAY 0.723404 (-5925 5925);
PAINT MONO (-5925 5925);
DISPLAY INVISIBLE (-5925 5925);
FORCEPROP 1 LAST BODY_TYPE PLUMBING
J 2
(-5925 5975);
DISPLAY 0.872340 (-5925 5975);
PAINT GREEN (-5925 5975);
DISPLAY INVISIBLE (-5925 5975);
FORCEPROP 1 LAST HDL_TAP TRUE
J 2
(-6250 5800);
DISPLAY 0.872340 (-6250 5800);
DISPLAY INVISIBLE (-6250 5800);
FORCEPROP 1 LAST PATH I256
J 2
(-5923 5925);
DISPLAY 0.872340 (-5923 5925);
PAINT GREEN (-5923 5925);
DISPLAY INVISIBLE (-5923 5925);
FORCEADD TAP..1
R 2
(-5725 5775);
FORCEPROP 3 LASTPIN (-5675 5775) SIG_NAME M_A_CPU1_SA_DQS_DP<3>
J 0
(-5665 5785);
DISPLAY 0.659574 (-5665 5785);
PAINT MONO (-5665 5785);
DISPLAY INVISIBLE (-5665 5785);
FORCEPROP 1 LASTPIN (-5675 5775) BN 3
J 2
(-5663 5783);
DISPLAY 0.489362 (-5663 5783);
PAINT GREEN (-5663 5783);
FORCEPROP 2 LAST CDS_LIB mstr_standard
J 2
(-5725 5775);
DISPLAY 0.723404 (-5725 5775);
PAINT MONO (-5725 5775);
DISPLAY INVISIBLE (-5725 5775);
FORCEPROP 1 LAST BODY_TYPE PLUMBING
J 2
(-5725 5825);
DISPLAY 0.872340 (-5725 5825);
PAINT GREEN (-5725 5825);
DISPLAY INVISIBLE (-5725 5825);
FORCEPROP 1 LAST HDL_TAP TRUE
J 2
(-6050 5650);
DISPLAY 0.872340 (-6050 5650);
DISPLAY INVISIBLE (-6050 5650);
FORCEPROP 1 LAST PATH I257
J 2
(-5723 5775);
DISPLAY 0.872340 (-5723 5775);
PAINT GREEN (-5723 5775);
DISPLAY INVISIBLE (-5723 5775);
FORCEADD TAP..1
R 2
(-5725 5675);
FORCEPROP 3 LASTPIN (-5675 5675) SIG_NAME M_A_CPU1_SA_DQS_DP<4>
J 0
(-5665 5685);
DISPLAY 0.659574 (-5665 5685);
PAINT MONO (-5665 5685);
DISPLAY INVISIBLE (-5665 5685);
FORCEPROP 1 LASTPIN (-5675 5675) BN 4
J 2
(-5663 5683);
DISPLAY 0.489362 (-5663 5683);
PAINT GREEN (-5663 5683);
FORCEPROP 2 LAST CDS_LIB mstr_standard
J 2
(-5725 5675);
DISPLAY 0.723404 (-5725 5675);
PAINT MONO (-5725 5675);
DISPLAY INVISIBLE (-5725 5675);
FORCEPROP 1 LAST BODY_TYPE PLUMBING
J 2
(-5725 5725);
DISPLAY 0.872340 (-5725 5725);
PAINT GREEN (-5725 5725);
DISPLAY INVISIBLE (-5725 5725);
FORCEPROP 1 LAST HDL_TAP TRUE
J 2
(-6050 5550);
DISPLAY 0.872340 (-6050 5550);
DISPLAY INVISIBLE (-6050 5550);
FORCEPROP 1 LAST PATH I258
J 2
(-5723 5675);
DISPLAY 0.872340 (-5723 5675);
PAINT GREEN (-5723 5675);
DISPLAY INVISIBLE (-5723 5675);
FORCEADD TAP..1
R 2
(-5925 5825);
FORCEPROP 3 LASTPIN (-5875 5825) SIG_NAME M_A_CPU1_SA_DQS_DN<2>
J 0
(-5865 5835);
DISPLAY 0.659574 (-5865 5835);
PAINT MONO (-5865 5835);
DISPLAY INVISIBLE (-5865 5835);
FORCEPROP 1 LASTPIN (-5875 5825) BN 2
J 2
(-5863 5833);
DISPLAY 0.489362 (-5863 5833);
PAINT GREEN (-5863 5833);
FORCEPROP 2 LAST CDS_LIB mstr_standard
J 2
(-5925 5825);
DISPLAY 0.723404 (-5925 5825);
PAINT MONO (-5925 5825);
DISPLAY INVISIBLE (-5925 5825);
FORCEPROP 1 LAST BODY_TYPE PLUMBING
J 2
(-5925 5875);
DISPLAY 0.872340 (-5925 5875);
PAINT GREEN (-5925 5875);
DISPLAY INVISIBLE (-5925 5875);
FORCEPROP 1 LAST HDL_TAP TRUE
J 2
(-6250 5700);
DISPLAY 0.872340 (-6250 5700);
DISPLAY INVISIBLE (-6250 5700);
FORCEPROP 1 LAST PATH I259
J 2
(-5923 5825);
DISPLAY 0.872340 (-5923 5825);
PAINT GREEN (-5923 5825);
DISPLAY INVISIBLE (-5923 5825);
FORCEADD TAP..1
R 2
(-5925 5725);
FORCEPROP 3 LASTPIN (-5875 5725) SIG_NAME M_A_CPU1_SA_DQS_DN<3>
J 0
(-5865 5735);
DISPLAY 0.659574 (-5865 5735);
PAINT MONO (-5865 5735);
DISPLAY INVISIBLE (-5865 5735);
FORCEPROP 1 LASTPIN (-5875 5725) BN 3
J 2
(-5863 5733);
DISPLAY 0.489362 (-5863 5733);
PAINT GREEN (-5863 5733);
FORCEPROP 2 LAST CDS_LIB mstr_standard
J 2
(-5925 5725);
DISPLAY 0.723404 (-5925 5725);
PAINT MONO (-5925 5725);
DISPLAY INVISIBLE (-5925 5725);
FORCEPROP 1 LAST BODY_TYPE PLUMBING
J 2
(-5925 5775);
DISPLAY 0.872340 (-5925 5775);
PAINT GREEN (-5925 5775);
DISPLAY INVISIBLE (-5925 5775);
FORCEPROP 1 LAST HDL_TAP TRUE
J 2
(-6250 5600);
DISPLAY 0.872340 (-6250 5600);
DISPLAY INVISIBLE (-6250 5600);
FORCEPROP 1 LAST PATH I260
J 2
(-5923 5725);
DISPLAY 0.872340 (-5923 5725);
PAINT GREEN (-5923 5725);
DISPLAY INVISIBLE (-5923 5725);
FORCEADD TAP..1
R 2
(-5725 5575);
FORCEPROP 3 LASTPIN (-5675 5575) SIG_NAME M_A_CPU1_SA_DQS_DP<5>
J 0
(-5665 5585);
DISPLAY 0.659574 (-5665 5585);
PAINT MONO (-5665 5585);
DISPLAY INVISIBLE (-5665 5585);
FORCEPROP 1 LASTPIN (-5675 5575) BN 5
J 2
(-5663 5583);
DISPLAY 0.489362 (-5663 5583);
PAINT GREEN (-5663 5583);
FORCEPROP 2 LAST CDS_LIB mstr_standard
J 2
(-5725 5575);
DISPLAY 0.723404 (-5725 5575);
PAINT MONO (-5725 5575);
DISPLAY INVISIBLE (-5725 5575);
FORCEPROP 1 LAST BODY_TYPE PLUMBING
J 2
(-5725 5625);
DISPLAY 0.872340 (-5725 5625);
PAINT GREEN (-5725 5625);
DISPLAY INVISIBLE (-5725 5625);
FORCEPROP 1 LAST HDL_TAP TRUE
J 2
(-6050 5450);
DISPLAY 0.872340 (-6050 5450);
DISPLAY INVISIBLE (-6050 5450);
FORCEPROP 1 LAST PATH I261
J 2
(-5723 5575);
DISPLAY 0.872340 (-5723 5575);
PAINT GREEN (-5723 5575);
DISPLAY INVISIBLE (-5723 5575);
FORCEADD TAP..1
R 2
(-5725 5375);
FORCEPROP 3 LASTPIN (-5675 5375) SIG_NAME M_A_CPU1_SA_DQS_DP<7>
J 0
(-5665 5385);
DISPLAY 0.659574 (-5665 5385);
PAINT MONO (-5665 5385);
DISPLAY INVISIBLE (-5665 5385);
FORCEPROP 1 LASTPIN (-5675 5375) BN 7
J 2
(-5663 5383);
DISPLAY 0.489362 (-5663 5383);
PAINT GREEN (-5663 5383);
FORCEPROP 2 LAST CDS_LIB mstr_standard
J 2
(-5725 5375);
DISPLAY 0.723404 (-5725 5375);
PAINT MONO (-5725 5375);
DISPLAY INVISIBLE (-5725 5375);
FORCEPROP 1 LAST BODY_TYPE PLUMBING
J 2
(-5725 5425);
DISPLAY 0.872340 (-5725 5425);
PAINT GREEN (-5725 5425);
DISPLAY INVISIBLE (-5725 5425);
FORCEPROP 1 LAST HDL_TAP TRUE
J 2
(-6050 5250);
DISPLAY 0.872340 (-6050 5250);
DISPLAY INVISIBLE (-6050 5250);
FORCEPROP 1 LAST PATH I262
J 2
(-5723 5375);
DISPLAY 0.872340 (-5723 5375);
PAINT GREEN (-5723 5375);
DISPLAY INVISIBLE (-5723 5375);
FORCEADD TAP..1
R 2
(-5725 5475);
FORCEPROP 3 LASTPIN (-5675 5475) SIG_NAME M_A_CPU1_SA_DQS_DP<6>
J 0
(-5665 5485);
DISPLAY 0.659574 (-5665 5485);
PAINT MONO (-5665 5485);
DISPLAY INVISIBLE (-5665 5485);
FORCEPROP 1 LASTPIN (-5675 5475) BN 6
J 2
(-5663 5483);
DISPLAY 0.489362 (-5663 5483);
PAINT GREEN (-5663 5483);
FORCEPROP 2 LAST CDS_LIB mstr_standard
J 2
(-5725 5475);
DISPLAY 0.723404 (-5725 5475);
PAINT MONO (-5725 5475);
DISPLAY INVISIBLE (-5725 5475);
FORCEPROP 1 LAST BODY_TYPE PLUMBING
J 2
(-5725 5525);
DISPLAY 0.872340 (-5725 5525);
PAINT GREEN (-5725 5525);
DISPLAY INVISIBLE (-5725 5525);
FORCEPROP 1 LAST HDL_TAP TRUE
J 2
(-6050 5350);
DISPLAY 0.872340 (-6050 5350);
DISPLAY INVISIBLE (-6050 5350);
FORCEPROP 1 LAST PATH I263
J 2
(-5723 5475);
DISPLAY 0.872340 (-5723 5475);
PAINT GREEN (-5723 5475);
DISPLAY INVISIBLE (-5723 5475);
FORCEADD TAP..1
R 2
(-5925 5625);
FORCEPROP 3 LASTPIN (-5875 5625) SIG_NAME M_A_CPU1_SA_DQS_DN<4>
J 0
(-5865 5635);
DISPLAY 0.659574 (-5865 5635);
PAINT MONO (-5865 5635);
DISPLAY INVISIBLE (-5865 5635);
FORCEPROP 1 LASTPIN (-5875 5625) BN 4
J 2
(-5863 5633);
DISPLAY 0.489362 (-5863 5633);
PAINT GREEN (-5863 5633);
FORCEPROP 2 LAST CDS_LIB mstr_standard
J 2
(-5925 5625);
DISPLAY 0.723404 (-5925 5625);
PAINT MONO (-5925 5625);
DISPLAY INVISIBLE (-5925 5625);
FORCEPROP 1 LAST BODY_TYPE PLUMBING
J 2
(-5925 5675);
DISPLAY 0.872340 (-5925 5675);
PAINT GREEN (-5925 5675);
DISPLAY INVISIBLE (-5925 5675);
FORCEPROP 1 LAST HDL_TAP TRUE
J 2
(-6250 5500);
DISPLAY 0.872340 (-6250 5500);
DISPLAY INVISIBLE (-6250 5500);
FORCEPROP 1 LAST PATH I264
J 2
(-5923 5625);
DISPLAY 0.872340 (-5923 5625);
PAINT GREEN (-5923 5625);
DISPLAY INVISIBLE (-5923 5625);
FORCEADD TAP..1
R 2
(-5925 5525);
FORCEPROP 3 LASTPIN (-5875 5525) SIG_NAME M_A_CPU1_SA_DQS_DN<5>
J 0
(-5865 5535);
DISPLAY 0.659574 (-5865 5535);
PAINT MONO (-5865 5535);
DISPLAY INVISIBLE (-5865 5535);
FORCEPROP 1 LASTPIN (-5875 5525) BN 5
J 2
(-5863 5533);
DISPLAY 0.489362 (-5863 5533);
PAINT GREEN (-5863 5533);
FORCEPROP 2 LAST CDS_LIB mstr_standard
J 2
(-5925 5525);
DISPLAY 0.723404 (-5925 5525);
PAINT MONO (-5925 5525);
DISPLAY INVISIBLE (-5925 5525);
FORCEPROP 1 LAST BODY_TYPE PLUMBING
J 2
(-5925 5575);
DISPLAY 0.872340 (-5925 5575);
PAINT GREEN (-5925 5575);
DISPLAY INVISIBLE (-5925 5575);
FORCEPROP 1 LAST HDL_TAP TRUE
J 2
(-6250 5400);
DISPLAY 0.872340 (-6250 5400);
DISPLAY INVISIBLE (-6250 5400);
FORCEPROP 1 LAST PATH I265
J 2
(-5923 5525);
DISPLAY 0.872340 (-5923 5525);
PAINT GREEN (-5923 5525);
DISPLAY INVISIBLE (-5923 5525);
FORCEADD TAP..1
R 2
(-5925 5425);
FORCEPROP 3 LASTPIN (-5875 5425) SIG_NAME M_A_CPU1_SA_DQS_DN<6>
J 0
(-5865 5435);
DISPLAY 0.659574 (-5865 5435);
PAINT MONO (-5865 5435);
DISPLAY INVISIBLE (-5865 5435);
FORCEPROP 1 LASTPIN (-5875 5425) BN 6
J 2
(-5863 5433);
DISPLAY 0.489362 (-5863 5433);
PAINT GREEN (-5863 5433);
FORCEPROP 2 LAST CDS_LIB mstr_standard
J 2
(-5925 5425);
DISPLAY 0.723404 (-5925 5425);
PAINT MONO (-5925 5425);
DISPLAY INVISIBLE (-5925 5425);
FORCEPROP 1 LAST BODY_TYPE PLUMBING
J 2
(-5925 5475);
DISPLAY 0.872340 (-5925 5475);
PAINT GREEN (-5925 5475);
DISPLAY INVISIBLE (-5925 5475);
FORCEPROP 1 LAST HDL_TAP TRUE
J 2
(-6250 5300);
DISPLAY 0.872340 (-6250 5300);
DISPLAY INVISIBLE (-6250 5300);
FORCEPROP 1 LAST PATH I266
J 2
(-5923 5425);
DISPLAY 0.872340 (-5923 5425);
PAINT GREEN (-5923 5425);
DISPLAY INVISIBLE (-5923 5425);
FORCEADD TAP..1
R 2
(-5725 5275);
FORCEPROP 3 LASTPIN (-5675 5275) SIG_NAME M_A_CPU1_SA_DQS_DP<8>
J 0
(-5665 5285);
DISPLAY 0.659574 (-5665 5285);
PAINT MONO (-5665 5285);
DISPLAY INVISIBLE (-5665 5285);
FORCEPROP 1 LASTPIN (-5675 5275) BN 8
J 2
(-5663 5283);
DISPLAY 0.489362 (-5663 5283);
PAINT GREEN (-5663 5283);
FORCEPROP 2 LAST CDS_LIB mstr_standard
J 2
(-5725 5275);
DISPLAY 0.723404 (-5725 5275);
PAINT MONO (-5725 5275);
DISPLAY INVISIBLE (-5725 5275);
FORCEPROP 1 LAST BODY_TYPE PLUMBING
J 2
(-5725 5325);
DISPLAY 0.872340 (-5725 5325);
PAINT GREEN (-5725 5325);
DISPLAY INVISIBLE (-5725 5325);
FORCEPROP 1 LAST HDL_TAP TRUE
J 2
(-6050 5150);
DISPLAY 0.872340 (-6050 5150);
DISPLAY INVISIBLE (-6050 5150);
FORCEPROP 1 LAST PATH I267
J 2
(-5723 5275);
DISPLAY 0.872340 (-5723 5275);
PAINT GREEN (-5723 5275);
DISPLAY INVISIBLE (-5723 5275);
FORCEADD TAP..1
R 2
(-5725 5175);
FORCEPROP 3 LASTPIN (-5675 5175) SIG_NAME M_A_CPU1_SA_DQS_DP<9>
J 0
(-5665 5185);
DISPLAY 0.659574 (-5665 5185);
PAINT MONO (-5665 5185);
DISPLAY INVISIBLE (-5665 5185);
FORCEPROP 1 LASTPIN (-5675 5175) BN 9
J 2
(-5663 5183);
DISPLAY 0.489362 (-5663 5183);
PAINT GREEN (-5663 5183);
FORCEPROP 2 LAST CDS_LIB mstr_standard
J 2
(-5725 5175);
DISPLAY 0.723404 (-5725 5175);
PAINT MONO (-5725 5175);
DISPLAY INVISIBLE (-5725 5175);
FORCEPROP 1 LAST BODY_TYPE PLUMBING
J 2
(-5725 5225);
DISPLAY 0.872340 (-5725 5225);
PAINT GREEN (-5725 5225);
DISPLAY INVISIBLE (-5725 5225);
FORCEPROP 1 LAST HDL_TAP TRUE
J 2
(-6050 5050);
DISPLAY 0.872340 (-6050 5050);
DISPLAY INVISIBLE (-6050 5050);
FORCEPROP 1 LAST PATH I268
J 2
(-5723 5175);
DISPLAY 0.872340 (-5723 5175);
PAINT GREEN (-5723 5175);
DISPLAY INVISIBLE (-5723 5175);
FORCEADD TAP..1
R 2
(-5925 5325);
FORCEPROP 3 LASTPIN (-5875 5325) SIG_NAME M_A_CPU1_SA_DQS_DN<7>
J 0
(-5865 5335);
DISPLAY 0.659574 (-5865 5335);
PAINT MONO (-5865 5335);
DISPLAY INVISIBLE (-5865 5335);
FORCEPROP 1 LASTPIN (-5875 5325) BN 7
J 2
(-5863 5333);
DISPLAY 0.489362 (-5863 5333);
PAINT GREEN (-5863 5333);
FORCEPROP 2 LAST CDS_LIB mstr_standard
J 2
(-5925 5325);
DISPLAY 0.723404 (-5925 5325);
PAINT MONO (-5925 5325);
DISPLAY INVISIBLE (-5925 5325);
FORCEPROP 1 LAST BODY_TYPE PLUMBING
J 2
(-5925 5375);
DISPLAY 0.872340 (-5925 5375);
PAINT GREEN (-5925 5375);
DISPLAY INVISIBLE (-5925 5375);
FORCEPROP 1 LAST HDL_TAP TRUE
J 2
(-6250 5200);
DISPLAY 0.872340 (-6250 5200);
DISPLAY INVISIBLE (-6250 5200);
FORCEPROP 1 LAST PATH I269
J 2
(-5923 5325);
DISPLAY 0.872340 (-5923 5325);
PAINT GREEN (-5923 5325);
DISPLAY INVISIBLE (-5923 5325);
FORCEADD TAP..1
R 2
(-5925 5225);
FORCEPROP 3 LASTPIN (-5875 5225) SIG_NAME M_A_CPU1_SA_DQS_DN<8>
J 0
(-5865 5235);
DISPLAY 0.659574 (-5865 5235);
PAINT MONO (-5865 5235);
DISPLAY INVISIBLE (-5865 5235);
FORCEPROP 1 LASTPIN (-5875 5225) BN 8
J 2
(-5863 5233);
DISPLAY 0.489362 (-5863 5233);
PAINT GREEN (-5863 5233);
FORCEPROP 2 LAST CDS_LIB mstr_standard
J 2
(-5925 5225);
DISPLAY 0.723404 (-5925 5225);
PAINT MONO (-5925 5225);
DISPLAY INVISIBLE (-5925 5225);
FORCEPROP 1 LAST BODY_TYPE PLUMBING
J 2
(-5925 5275);
DISPLAY 0.872340 (-5925 5275);
PAINT GREEN (-5925 5275);
DISPLAY INVISIBLE (-5925 5275);
FORCEPROP 1 LAST HDL_TAP TRUE
J 2
(-6250 5100);
DISPLAY 0.872340 (-6250 5100);
DISPLAY INVISIBLE (-6250 5100);
FORCEPROP 1 LAST PATH I270
J 2
(-5923 5225);
DISPLAY 0.872340 (-5923 5225);
PAINT GREEN (-5923 5225);
DISPLAY INVISIBLE (-5923 5225);
FORCEADD TAP..1
R 2
(-5925 5125);
FORCEPROP 3 LASTPIN (-5875 5125) SIG_NAME M_A_CPU1_SA_DQS_DN<9>
J 0
(-5865 5135);
DISPLAY 0.659574 (-5865 5135);
PAINT MONO (-5865 5135);
DISPLAY INVISIBLE (-5865 5135);
FORCEPROP 1 LASTPIN (-5875 5125) BN 9
J 2
(-5863 5133);
DISPLAY 0.489362 (-5863 5133);
PAINT GREEN (-5863 5133);
FORCEPROP 2 LAST CDS_LIB mstr_standard
J 2
(-5925 5125);
DISPLAY 0.723404 (-5925 5125);
PAINT MONO (-5925 5125);
DISPLAY INVISIBLE (-5925 5125);
FORCEPROP 1 LAST BODY_TYPE PLUMBING
J 2
(-5925 5175);
DISPLAY 0.872340 (-5925 5175);
PAINT GREEN (-5925 5175);
DISPLAY INVISIBLE (-5925 5175);
FORCEPROP 1 LAST HDL_TAP TRUE
J 2
(-6250 5000);
DISPLAY 0.872340 (-6250 5000);
DISPLAY INVISIBLE (-6250 5000);
FORCEPROP 1 LAST PATH I271
J 2
(-5923 5125);
DISPLAY 0.872340 (-5923 5125);
PAINT GREEN (-5923 5125);
DISPLAY INVISIBLE (-5923 5125);
FORCEADD TAP..1
R 2
(-5725 5025);
FORCEPROP 3 LASTPIN (-5675 5025) SIG_NAME M_A_CPU1_SB_DQS_DP<0>
J 0
(-5665 5035);
DISPLAY 0.659574 (-5665 5035);
PAINT MONO (-5665 5035);
DISPLAY INVISIBLE (-5665 5035);
FORCEPROP 1 LASTPIN (-5675 5025) BN 0
J 2
(-5663 5033);
DISPLAY 0.489362 (-5663 5033);
PAINT GREEN (-5663 5033);
FORCEPROP 2 LAST CDS_LIB mstr_standard
J 2
(-5725 5025);
DISPLAY 0.723404 (-5725 5025);
PAINT MONO (-5725 5025);
DISPLAY INVISIBLE (-5725 5025);
FORCEPROP 1 LAST BODY_TYPE PLUMBING
J 2
(-5725 5075);
DISPLAY 0.872340 (-5725 5075);
PAINT GREEN (-5725 5075);
DISPLAY INVISIBLE (-5725 5075);
FORCEPROP 1 LAST HDL_TAP TRUE
J 2
(-6050 4900);
DISPLAY 0.872340 (-6050 4900);
DISPLAY INVISIBLE (-6050 4900);
FORCEPROP 1 LAST PATH I272
J 2
(-5723 5025);
DISPLAY 0.872340 (-5723 5025);
PAINT GREEN (-5723 5025);
DISPLAY INVISIBLE (-5723 5025);
FORCEADD TAP..1
R 2
(-5725 4925);
FORCEPROP 3 LASTPIN (-5675 4925) SIG_NAME M_A_CPU1_SB_DQS_DP<1>
J 0
(-5665 4935);
DISPLAY 0.659574 (-5665 4935);
PAINT MONO (-5665 4935);
DISPLAY INVISIBLE (-5665 4935);
FORCEPROP 1 LASTPIN (-5675 4925) BN 1
J 2
(-5663 4933);
DISPLAY 0.489362 (-5663 4933);
PAINT GREEN (-5663 4933);
FORCEPROP 2 LAST CDS_LIB mstr_standard
J 2
(-5725 4925);
DISPLAY 0.723404 (-5725 4925);
PAINT MONO (-5725 4925);
DISPLAY INVISIBLE (-5725 4925);
FORCEPROP 1 LAST BODY_TYPE PLUMBING
J 2
(-5725 4975);
DISPLAY 0.872340 (-5725 4975);
PAINT GREEN (-5725 4975);
DISPLAY INVISIBLE (-5725 4975);
FORCEPROP 1 LAST HDL_TAP TRUE
J 2
(-6050 4800);
DISPLAY 0.872340 (-6050 4800);
DISPLAY INVISIBLE (-6050 4800);
FORCEPROP 1 LAST PATH I273
J 2
(-5723 4925);
DISPLAY 0.872340 (-5723 4925);
PAINT GREEN (-5723 4925);
DISPLAY INVISIBLE (-5723 4925);
FORCEADD TAP..1
R 2
(-5925 4975);
FORCEPROP 3 LASTPIN (-5875 4975) SIG_NAME M_A_CPU1_SB_DQS_DN<0>
J 0
(-5865 4985);
DISPLAY 0.659574 (-5865 4985);
PAINT MONO (-5865 4985);
DISPLAY INVISIBLE (-5865 4985);
FORCEPROP 1 LASTPIN (-5875 4975) BN 0
J 2
(-5863 4983);
DISPLAY 0.489362 (-5863 4983);
PAINT GREEN (-5863 4983);
FORCEPROP 2 LAST CDS_LIB mstr_standard
J 2
(-5925 4975);
DISPLAY 0.723404 (-5925 4975);
PAINT MONO (-5925 4975);
DISPLAY INVISIBLE (-5925 4975);
FORCEPROP 1 LAST BODY_TYPE PLUMBING
J 2
(-5925 5025);
DISPLAY 0.872340 (-5925 5025);
PAINT GREEN (-5925 5025);
DISPLAY INVISIBLE (-5925 5025);
FORCEPROP 1 LAST HDL_TAP TRUE
J 2
(-6250 4850);
DISPLAY 0.872340 (-6250 4850);
DISPLAY INVISIBLE (-6250 4850);
FORCEPROP 1 LAST PATH I274
J 2
(-5923 4975);
DISPLAY 0.872340 (-5923 4975);
PAINT GREEN (-5923 4975);
DISPLAY INVISIBLE (-5923 4975);
FORCEADD TAP..1
R 2
(-5925 4875);
FORCEPROP 3 LASTPIN (-5875 4875) SIG_NAME M_A_CPU1_SB_DQS_DN<1>
J 0
(-5865 4885);
DISPLAY 0.659574 (-5865 4885);
PAINT MONO (-5865 4885);
DISPLAY INVISIBLE (-5865 4885);
FORCEPROP 1 LASTPIN (-5875 4875) BN 1
J 2
(-5863 4883);
DISPLAY 0.489362 (-5863 4883);
PAINT GREEN (-5863 4883);
FORCEPROP 2 LAST CDS_LIB mstr_standard
J 2
(-5925 4875);
DISPLAY 0.723404 (-5925 4875);
PAINT MONO (-5925 4875);
DISPLAY INVISIBLE (-5925 4875);
FORCEPROP 1 LAST BODY_TYPE PLUMBING
J 2
(-5925 4925);
DISPLAY 0.872340 (-5925 4925);
PAINT GREEN (-5925 4925);
DISPLAY INVISIBLE (-5925 4925);
FORCEPROP 1 LAST HDL_TAP TRUE
J 2
(-6250 4750);
DISPLAY 0.872340 (-6250 4750);
DISPLAY INVISIBLE (-6250 4750);
FORCEPROP 1 LAST PATH I275
J 2
(-5923 4875);
DISPLAY 0.872340 (-5923 4875);
PAINT GREEN (-5923 4875);
DISPLAY INVISIBLE (-5923 4875);
FORCEADD TAP..1
R 2
(-5725 4825);
FORCEPROP 3 LASTPIN (-5675 4825) SIG_NAME M_A_CPU1_SB_DQS_DP<2>
J 0
(-5665 4835);
DISPLAY 0.659574 (-5665 4835);
PAINT MONO (-5665 4835);
DISPLAY INVISIBLE (-5665 4835);
FORCEPROP 1 LASTPIN (-5675 4825) BN 2
J 2
(-5663 4833);
DISPLAY 0.489362 (-5663 4833);
PAINT GREEN (-5663 4833);
FORCEPROP 2 LAST CDS_LIB mstr_standard
J 2
(-5725 4825);
DISPLAY 0.723404 (-5725 4825);
PAINT MONO (-5725 4825);
DISPLAY INVISIBLE (-5725 4825);
FORCEPROP 1 LAST BODY_TYPE PLUMBING
J 2
(-5725 4875);
DISPLAY 0.872340 (-5725 4875);
PAINT GREEN (-5725 4875);
DISPLAY INVISIBLE (-5725 4875);
FORCEPROP 1 LAST HDL_TAP TRUE
J 2
(-6050 4700);
DISPLAY 0.872340 (-6050 4700);
DISPLAY INVISIBLE (-6050 4700);
FORCEPROP 1 LAST PATH I276
J 2
(-5723 4825);
DISPLAY 0.872340 (-5723 4825);
PAINT GREEN (-5723 4825);
DISPLAY INVISIBLE (-5723 4825);
FORCEADD TAP..1
R 2
(-5725 4725);
FORCEPROP 3 LASTPIN (-5675 4725) SIG_NAME M_A_CPU1_SB_DQS_DP<3>
J 0
(-5665 4735);
DISPLAY 0.659574 (-5665 4735);
PAINT MONO (-5665 4735);
DISPLAY INVISIBLE (-5665 4735);
FORCEPROP 1 LASTPIN (-5675 4725) BN 3
J 2
(-5663 4733);
DISPLAY 0.489362 (-5663 4733);
PAINT GREEN (-5663 4733);
FORCEPROP 2 LAST CDS_LIB mstr_standard
J 2
(-5725 4725);
DISPLAY 0.723404 (-5725 4725);
PAINT MONO (-5725 4725);
DISPLAY INVISIBLE (-5725 4725);
FORCEPROP 1 LAST BODY_TYPE PLUMBING
J 2
(-5725 4775);
DISPLAY 0.872340 (-5725 4775);
PAINT GREEN (-5725 4775);
DISPLAY INVISIBLE (-5725 4775);
FORCEPROP 1 LAST HDL_TAP TRUE
J 2
(-6050 4600);
DISPLAY 0.872340 (-6050 4600);
DISPLAY INVISIBLE (-6050 4600);
FORCEPROP 1 LAST PATH I277
J 2
(-5723 4725);
DISPLAY 0.872340 (-5723 4725);
PAINT GREEN (-5723 4725);
DISPLAY INVISIBLE (-5723 4725);
FORCEADD TAP..1
R 2
(-5725 4625);
FORCEPROP 3 LASTPIN (-5675 4625) SIG_NAME M_A_CPU1_SB_DQS_DP<4>
J 0
(-5665 4635);
DISPLAY 0.659574 (-5665 4635);
PAINT MONO (-5665 4635);
DISPLAY INVISIBLE (-5665 4635);
FORCEPROP 1 LASTPIN (-5675 4625) BN 4
J 2
(-5663 4633);
DISPLAY 0.489362 (-5663 4633);
PAINT GREEN (-5663 4633);
FORCEPROP 2 LAST CDS_LIB mstr_standard
J 2
(-5725 4625);
DISPLAY 0.723404 (-5725 4625);
PAINT MONO (-5725 4625);
DISPLAY INVISIBLE (-5725 4625);
FORCEPROP 1 LAST BODY_TYPE PLUMBING
J 2
(-5725 4675);
DISPLAY 0.872340 (-5725 4675);
PAINT GREEN (-5725 4675);
DISPLAY INVISIBLE (-5725 4675);
FORCEPROP 1 LAST HDL_TAP TRUE
J 2
(-6050 4500);
DISPLAY 0.872340 (-6050 4500);
DISPLAY INVISIBLE (-6050 4500);
FORCEPROP 1 LAST PATH I278
J 2
(-5723 4625);
DISPLAY 0.872340 (-5723 4625);
PAINT GREEN (-5723 4625);
DISPLAY INVISIBLE (-5723 4625);
FORCEADD TAP..1
R 2
(-5925 4775);
FORCEPROP 3 LASTPIN (-5875 4775) SIG_NAME M_A_CPU1_SB_DQS_DN<2>
J 0
(-5865 4785);
DISPLAY 0.659574 (-5865 4785);
PAINT MONO (-5865 4785);
DISPLAY INVISIBLE (-5865 4785);
FORCEPROP 1 LASTPIN (-5875 4775) BN 2
J 2
(-5863 4783);
DISPLAY 0.489362 (-5863 4783);
PAINT GREEN (-5863 4783);
FORCEPROP 2 LAST CDS_LIB mstr_standard
J 2
(-5925 4775);
DISPLAY 0.723404 (-5925 4775);
PAINT MONO (-5925 4775);
DISPLAY INVISIBLE (-5925 4775);
FORCEPROP 1 LAST BODY_TYPE PLUMBING
J 2
(-5925 4825);
DISPLAY 0.872340 (-5925 4825);
PAINT GREEN (-5925 4825);
DISPLAY INVISIBLE (-5925 4825);
FORCEPROP 1 LAST HDL_TAP TRUE
J 2
(-6250 4650);
DISPLAY 0.872340 (-6250 4650);
DISPLAY INVISIBLE (-6250 4650);
FORCEPROP 1 LAST PATH I279
J 2
(-5923 4775);
DISPLAY 0.872340 (-5923 4775);
PAINT GREEN (-5923 4775);
DISPLAY INVISIBLE (-5923 4775);
FORCEADD TAP..1
R 2
(-5925 4675);
FORCEPROP 3 LASTPIN (-5875 4675) SIG_NAME M_A_CPU1_SB_DQS_DN<3>
J 0
(-5865 4685);
DISPLAY 0.659574 (-5865 4685);
PAINT MONO (-5865 4685);
DISPLAY INVISIBLE (-5865 4685);
FORCEPROP 1 LASTPIN (-5875 4675) BN 3
J 2
(-5863 4683);
DISPLAY 0.489362 (-5863 4683);
PAINT GREEN (-5863 4683);
FORCEPROP 2 LAST CDS_LIB mstr_standard
J 2
(-5925 4675);
DISPLAY 0.723404 (-5925 4675);
PAINT MONO (-5925 4675);
DISPLAY INVISIBLE (-5925 4675);
FORCEPROP 1 LAST BODY_TYPE PLUMBING
J 2
(-5925 4725);
DISPLAY 0.872340 (-5925 4725);
PAINT GREEN (-5925 4725);
DISPLAY INVISIBLE (-5925 4725);
FORCEPROP 1 LAST HDL_TAP TRUE
J 2
(-6250 4550);
DISPLAY 0.872340 (-6250 4550);
DISPLAY INVISIBLE (-6250 4550);
FORCEPROP 1 LAST PATH I280
J 2
(-5923 4675);
DISPLAY 0.872340 (-5923 4675);
PAINT GREEN (-5923 4675);
DISPLAY INVISIBLE (-5923 4675);
FORCEADD TAP..1
R 2
(-5725 4525);
FORCEPROP 3 LASTPIN (-5675 4525) SIG_NAME M_A_CPU1_SB_DQS_DP<5>
J 0
(-5665 4535);
DISPLAY 0.659574 (-5665 4535);
PAINT MONO (-5665 4535);
DISPLAY INVISIBLE (-5665 4535);
FORCEPROP 1 LASTPIN (-5675 4525) BN 5
J 2
(-5663 4533);
DISPLAY 0.489362 (-5663 4533);
PAINT GREEN (-5663 4533);
FORCEPROP 2 LAST CDS_LIB mstr_standard
J 2
(-5725 4525);
DISPLAY 0.723404 (-5725 4525);
PAINT MONO (-5725 4525);
DISPLAY INVISIBLE (-5725 4525);
FORCEPROP 1 LAST BODY_TYPE PLUMBING
J 2
(-5725 4575);
DISPLAY 0.872340 (-5725 4575);
PAINT GREEN (-5725 4575);
DISPLAY INVISIBLE (-5725 4575);
FORCEPROP 1 LAST HDL_TAP TRUE
J 2
(-6050 4400);
DISPLAY 0.872340 (-6050 4400);
DISPLAY INVISIBLE (-6050 4400);
FORCEPROP 1 LAST PATH I281
J 2
(-5723 4525);
DISPLAY 0.872340 (-5723 4525);
PAINT GREEN (-5723 4525);
DISPLAY INVISIBLE (-5723 4525);
FORCEADD TAP..1
R 2
(-5725 4425);
FORCEPROP 3 LASTPIN (-5675 4425) SIG_NAME M_A_CPU1_SB_DQS_DP<6>
J 0
(-5665 4435);
DISPLAY 0.659574 (-5665 4435);
PAINT MONO (-5665 4435);
DISPLAY INVISIBLE (-5665 4435);
FORCEPROP 1 LASTPIN (-5675 4425) BN 6
J 2
(-5663 4433);
DISPLAY 0.489362 (-5663 4433);
PAINT GREEN (-5663 4433);
FORCEPROP 2 LAST CDS_LIB mstr_standard
J 2
(-5725 4425);
DISPLAY 0.723404 (-5725 4425);
PAINT MONO (-5725 4425);
DISPLAY INVISIBLE (-5725 4425);
FORCEPROP 1 LAST BODY_TYPE PLUMBING
J 2
(-5725 4475);
DISPLAY 0.872340 (-5725 4475);
PAINT GREEN (-5725 4475);
DISPLAY INVISIBLE (-5725 4475);
FORCEPROP 1 LAST HDL_TAP TRUE
J 2
(-6050 4300);
DISPLAY 0.872340 (-6050 4300);
DISPLAY INVISIBLE (-6050 4300);
FORCEPROP 1 LAST PATH I282
J 2
(-5723 4425);
DISPLAY 0.872340 (-5723 4425);
PAINT GREEN (-5723 4425);
DISPLAY INVISIBLE (-5723 4425);
FORCEADD TAP..1
R 2
(-5925 4575);
FORCEPROP 3 LASTPIN (-5875 4575) SIG_NAME M_A_CPU1_SB_DQS_DN<4>
J 0
(-5865 4585);
DISPLAY 0.659574 (-5865 4585);
PAINT MONO (-5865 4585);
DISPLAY INVISIBLE (-5865 4585);
FORCEPROP 1 LASTPIN (-5875 4575) BN 4
J 2
(-5863 4583);
DISPLAY 0.489362 (-5863 4583);
PAINT GREEN (-5863 4583);
FORCEPROP 2 LAST CDS_LIB mstr_standard
J 2
(-5925 4575);
DISPLAY 0.723404 (-5925 4575);
PAINT MONO (-5925 4575);
DISPLAY INVISIBLE (-5925 4575);
FORCEPROP 1 LAST BODY_TYPE PLUMBING
J 2
(-5925 4625);
DISPLAY 0.872340 (-5925 4625);
PAINT GREEN (-5925 4625);
DISPLAY INVISIBLE (-5925 4625);
FORCEPROP 1 LAST HDL_TAP TRUE
J 2
(-6250 4450);
DISPLAY 0.872340 (-6250 4450);
DISPLAY INVISIBLE (-6250 4450);
FORCEPROP 1 LAST PATH I283
J 2
(-5923 4575);
DISPLAY 0.872340 (-5923 4575);
PAINT GREEN (-5923 4575);
DISPLAY INVISIBLE (-5923 4575);
FORCEADD TAP..1
R 2
(-5925 4475);
FORCEPROP 3 LASTPIN (-5875 4475) SIG_NAME M_A_CPU1_SB_DQS_DN<5>
J 0
(-5865 4485);
DISPLAY 0.659574 (-5865 4485);
PAINT MONO (-5865 4485);
DISPLAY INVISIBLE (-5865 4485);
FORCEPROP 1 LASTPIN (-5875 4475) BN 5
J 2
(-5863 4483);
DISPLAY 0.489362 (-5863 4483);
PAINT GREEN (-5863 4483);
FORCEPROP 2 LAST CDS_LIB mstr_standard
J 2
(-5925 4475);
DISPLAY 0.723404 (-5925 4475);
PAINT MONO (-5925 4475);
DISPLAY INVISIBLE (-5925 4475);
FORCEPROP 1 LAST BODY_TYPE PLUMBING
J 2
(-5925 4525);
DISPLAY 0.872340 (-5925 4525);
PAINT GREEN (-5925 4525);
DISPLAY INVISIBLE (-5925 4525);
FORCEPROP 1 LAST HDL_TAP TRUE
J 2
(-6250 4350);
DISPLAY 0.872340 (-6250 4350);
DISPLAY INVISIBLE (-6250 4350);
FORCEPROP 1 LAST PATH I284
J 2
(-5923 4475);
DISPLAY 0.872340 (-5923 4475);
PAINT GREEN (-5923 4475);
DISPLAY INVISIBLE (-5923 4475);
FORCEADD TAP..1
R 2
(-5925 4375);
FORCEPROP 3 LASTPIN (-5875 4375) SIG_NAME M_A_CPU1_SB_DQS_DN<6>
J 0
(-5865 4385);
DISPLAY 0.659574 (-5865 4385);
PAINT MONO (-5865 4385);
DISPLAY INVISIBLE (-5865 4385);
FORCEPROP 1 LASTPIN (-5875 4375) BN 6
J 2
(-5863 4383);
DISPLAY 0.489362 (-5863 4383);
PAINT GREEN (-5863 4383);
FORCEPROP 2 LAST CDS_LIB mstr_standard
J 2
(-5925 4375);
DISPLAY 0.723404 (-5925 4375);
PAINT MONO (-5925 4375);
DISPLAY INVISIBLE (-5925 4375);
FORCEPROP 1 LAST BODY_TYPE PLUMBING
J 2
(-5925 4425);
DISPLAY 0.872340 (-5925 4425);
PAINT GREEN (-5925 4425);
DISPLAY INVISIBLE (-5925 4425);
FORCEPROP 1 LAST HDL_TAP TRUE
J 2
(-6250 4250);
DISPLAY 0.872340 (-6250 4250);
DISPLAY INVISIBLE (-6250 4250);
FORCEPROP 1 LAST PATH I285
J 2
(-5923 4375);
DISPLAY 0.872340 (-5923 4375);
PAINT GREEN (-5923 4375);
DISPLAY INVISIBLE (-5923 4375);
FORCEADD TAP..1
R 2
(-5725 4325);
FORCEPROP 3 LASTPIN (-5675 4325) SIG_NAME M_A_CPU1_SB_DQS_DP<7>
J 0
(-5665 4335);
DISPLAY 0.659574 (-5665 4335);
PAINT MONO (-5665 4335);
DISPLAY INVISIBLE (-5665 4335);
FORCEPROP 1 LASTPIN (-5675 4325) BN 7
J 2
(-5663 4333);
DISPLAY 0.489362 (-5663 4333);
PAINT GREEN (-5663 4333);
FORCEPROP 2 LAST CDS_LIB mstr_standard
J 2
(-5725 4325);
DISPLAY 0.723404 (-5725 4325);
PAINT MONO (-5725 4325);
DISPLAY INVISIBLE (-5725 4325);
FORCEPROP 1 LAST BODY_TYPE PLUMBING
J 2
(-5725 4375);
DISPLAY 0.872340 (-5725 4375);
PAINT GREEN (-5725 4375);
DISPLAY INVISIBLE (-5725 4375);
FORCEPROP 1 LAST HDL_TAP TRUE
J 2
(-6050 4200);
DISPLAY 0.872340 (-6050 4200);
DISPLAY INVISIBLE (-6050 4200);
FORCEPROP 1 LAST PATH I286
J 2
(-5723 4325);
DISPLAY 0.872340 (-5723 4325);
PAINT GREEN (-5723 4325);
DISPLAY INVISIBLE (-5723 4325);
FORCEADD TAP..1
R 2
(-5725 4225);
FORCEPROP 3 LASTPIN (-5675 4225) SIG_NAME M_A_CPU1_SB_DQS_DP<8>
J 0
(-5665 4235);
DISPLAY 0.659574 (-5665 4235);
PAINT MONO (-5665 4235);
DISPLAY INVISIBLE (-5665 4235);
FORCEPROP 1 LASTPIN (-5675 4225) BN 8
J 2
(-5663 4233);
DISPLAY 0.489362 (-5663 4233);
PAINT GREEN (-5663 4233);
FORCEPROP 2 LAST CDS_LIB mstr_standard
J 2
(-5725 4225);
DISPLAY 0.723404 (-5725 4225);
PAINT MONO (-5725 4225);
DISPLAY INVISIBLE (-5725 4225);
FORCEPROP 1 LAST BODY_TYPE PLUMBING
J 2
(-5725 4275);
DISPLAY 0.872340 (-5725 4275);
PAINT GREEN (-5725 4275);
DISPLAY INVISIBLE (-5725 4275);
FORCEPROP 1 LAST HDL_TAP TRUE
J 2
(-6050 4100);
DISPLAY 0.872340 (-6050 4100);
DISPLAY INVISIBLE (-6050 4100);
FORCEPROP 1 LAST PATH I287
J 2
(-5723 4225);
DISPLAY 0.872340 (-5723 4225);
PAINT GREEN (-5723 4225);
DISPLAY INVISIBLE (-5723 4225);
FORCEADD TAP..1
R 2
(-5725 4125);
FORCEPROP 3 LASTPIN (-5675 4125) SIG_NAME M_A_CPU1_SB_DQS_DP<9>
J 0
(-5665 4135);
DISPLAY 0.659574 (-5665 4135);
PAINT MONO (-5665 4135);
DISPLAY INVISIBLE (-5665 4135);
FORCEPROP 1 LASTPIN (-5675 4125) BN 9
J 2
(-5663 4133);
DISPLAY 0.489362 (-5663 4133);
PAINT GREEN (-5663 4133);
FORCEPROP 2 LAST CDS_LIB mstr_standard
J 2
(-5725 4125);
DISPLAY 0.723404 (-5725 4125);
PAINT MONO (-5725 4125);
DISPLAY INVISIBLE (-5725 4125);
FORCEPROP 1 LAST BODY_TYPE PLUMBING
J 2
(-5725 4175);
DISPLAY 0.872340 (-5725 4175);
PAINT GREEN (-5725 4175);
DISPLAY INVISIBLE (-5725 4175);
FORCEPROP 1 LAST HDL_TAP TRUE
J 2
(-6050 4000);
DISPLAY 0.872340 (-6050 4000);
DISPLAY INVISIBLE (-6050 4000);
FORCEPROP 1 LAST PATH I288
J 2
(-5723 4125);
DISPLAY 0.872340 (-5723 4125);
PAINT GREEN (-5723 4125);
DISPLAY INVISIBLE (-5723 4125);
FORCEADD TAP..1
R 2
(-5925 4275);
FORCEPROP 3 LASTPIN (-5875 4275) SIG_NAME M_A_CPU1_SB_DQS_DN<7>
J 0
(-5865 4285);
DISPLAY 0.659574 (-5865 4285);
PAINT MONO (-5865 4285);
DISPLAY INVISIBLE (-5865 4285);
FORCEPROP 1 LASTPIN (-5875 4275) BN 7
J 2
(-5863 4283);
DISPLAY 0.489362 (-5863 4283);
PAINT GREEN (-5863 4283);
FORCEPROP 2 LAST CDS_LIB mstr_standard
J 2
(-5925 4275);
DISPLAY 0.723404 (-5925 4275);
PAINT MONO (-5925 4275);
DISPLAY INVISIBLE (-5925 4275);
FORCEPROP 1 LAST BODY_TYPE PLUMBING
J 2
(-5925 4325);
DISPLAY 0.872340 (-5925 4325);
PAINT GREEN (-5925 4325);
DISPLAY INVISIBLE (-5925 4325);
FORCEPROP 1 LAST HDL_TAP TRUE
J 2
(-6250 4150);
DISPLAY 0.872340 (-6250 4150);
DISPLAY INVISIBLE (-6250 4150);
FORCEPROP 1 LAST PATH I289
J 2
(-5923 4275);
DISPLAY 0.872340 (-5923 4275);
PAINT GREEN (-5923 4275);
DISPLAY INVISIBLE (-5923 4275);
FORCEADD TAP..1
R 2
(-5925 4175);
FORCEPROP 3 LASTPIN (-5875 4175) SIG_NAME M_A_CPU1_SB_DQS_DN<8>
J 0
(-5865 4185);
DISPLAY 0.659574 (-5865 4185);
PAINT MONO (-5865 4185);
DISPLAY INVISIBLE (-5865 4185);
FORCEPROP 1 LASTPIN (-5875 4175) BN 8
J 2
(-5863 4183);
DISPLAY 0.489362 (-5863 4183);
PAINT GREEN (-5863 4183);
FORCEPROP 2 LAST CDS_LIB mstr_standard
J 2
(-5925 4175);
DISPLAY 0.723404 (-5925 4175);
PAINT MONO (-5925 4175);
DISPLAY INVISIBLE (-5925 4175);
FORCEPROP 1 LAST BODY_TYPE PLUMBING
J 2
(-5925 4225);
DISPLAY 0.872340 (-5925 4225);
PAINT GREEN (-5925 4225);
DISPLAY INVISIBLE (-5925 4225);
FORCEPROP 1 LAST HDL_TAP TRUE
J 2
(-6250 4050);
DISPLAY 0.872340 (-6250 4050);
DISPLAY INVISIBLE (-6250 4050);
FORCEPROP 1 LAST PATH I290
J 2
(-5923 4175);
DISPLAY 0.872340 (-5923 4175);
PAINT GREEN (-5923 4175);
DISPLAY INVISIBLE (-5923 4175);
FORCEADD OFFPAGE..3
R 2
(-6625 6050);
FORCEPROP 2 LAST $XR0 97 
J 0
(-6874 6050);
DISPLAY 0.638298 (-6874 6050);
PAINT MONO (-6874 6050);
FORCEPROP 2 LAST PATH I291
J 0
(-6900 6100);
DISPLAY 1.021277 (-6900 6100);
DISPLAY INVISIBLE (-6900 6100);
FORCEPROP 1 LAST COMMENT_BODY TRUE
J 2
(-6575 5950);
DISPLAY 0.872340 (-6575 5950);
PAINT GREEN (-6575 5950);
DISPLAY INVISIBLE (-6575 5950);
FORCEPROP 1 LAST OFFPAGE TRUE
J 2
(-6950 5925);
DISPLAY 0.872340 (-6950 5925);
PAINT GREEN (-6950 5925);
DISPLAY INVISIBLE (-6950 5925);
FORCEPROP 2 LAST CDS_LIB standard
J 0
(-6625 6050);
DISPLAY INVISIBLE (-6625 6050);
FORCEADD OFFPAGE..3
R 2
(-6625 6100);
FORCEPROP 2 LAST $XR0 97 
J 0
(-6874 6100);
DISPLAY 0.638298 (-6874 6100);
PAINT MONO (-6874 6100);
FORCEPROP 2 LAST PATH I292
J 0
(-6900 6150);
DISPLAY 1.021277 (-6900 6150);
DISPLAY INVISIBLE (-6900 6150);
FORCEPROP 1 LAST COMMENT_BODY TRUE
J 2
(-6575 6000);
DISPLAY 0.872340 (-6575 6000);
PAINT GREEN (-6575 6000);
DISPLAY INVISIBLE (-6575 6000);
FORCEPROP 1 LAST OFFPAGE TRUE
J 2
(-6950 5975);
DISPLAY 0.872340 (-6950 5975);
PAINT GREEN (-6950 5975);
DISPLAY INVISIBLE (-6950 5975);
FORCEPROP 2 LAST CDS_LIB standard
J 0
(-6625 6100);
DISPLAY INVISIBLE (-6625 6100);
FORCEADD OFFPAGE..3
R 2
(-6625 5050);
FORCEPROP 2 LAST $XR0 97 
J 0
(-6874 5050);
DISPLAY 0.638298 (-6874 5050);
PAINT MONO (-6874 5050);
FORCEPROP 2 LAST PATH I293
J 0
(-6900 5100);
DISPLAY 1.021277 (-6900 5100);
DISPLAY INVISIBLE (-6900 5100);
FORCEPROP 1 LAST COMMENT_BODY TRUE
J 2
(-6575 4950);
DISPLAY 0.872340 (-6575 4950);
PAINT GREEN (-6575 4950);
DISPLAY INVISIBLE (-6575 4950);
FORCEPROP 1 LAST OFFPAGE TRUE
J 2
(-6950 4925);
DISPLAY 0.872340 (-6950 4925);
PAINT GREEN (-6950 4925);
DISPLAY INVISIBLE (-6950 4925);
FORCEPROP 2 LAST CDS_LIB standard
J 0
(-6625 5050);
DISPLAY INVISIBLE (-6625 5050);
FORCEADD OFFPAGE..3
R 2
(-6625 5000);
FORCEPROP 2 LAST $XR0 97 
J 0
(-6874 5000);
DISPLAY 0.638298 (-6874 5000);
PAINT MONO (-6874 5000);
FORCEPROP 2 LAST PATH I294
J 0
(-6900 5050);
DISPLAY 1.021277 (-6900 5050);
DISPLAY INVISIBLE (-6900 5050);
FORCEPROP 1 LAST COMMENT_BODY TRUE
J 2
(-6575 4900);
DISPLAY 0.872340 (-6575 4900);
PAINT GREEN (-6575 4900);
DISPLAY INVISIBLE (-6575 4900);
FORCEPROP 1 LAST OFFPAGE TRUE
J 2
(-6950 4875);
DISPLAY 0.872340 (-6950 4875);
PAINT GREEN (-6950 4875);
DISPLAY INVISIBLE (-6950 4875);
FORCEPROP 2 LAST CDS_LIB standard
J 0
(-6625 5000);
DISPLAY INVISIBLE (-6625 5000);
FORCEADD TAP..1
R 2
(-5925 4075);
FORCEPROP 3 LASTPIN (-5875 4075) SIG_NAME M_A_CPU1_SB_DQS_DN<9>
J 0
(-5865 4085);
DISPLAY 0.659574 (-5865 4085);
PAINT MONO (-5865 4085);
DISPLAY INVISIBLE (-5865 4085);
FORCEPROP 1 LASTPIN (-5875 4075) BN 9
J 2
(-5863 4083);
DISPLAY 0.489362 (-5863 4083);
PAINT GREEN (-5863 4083);
FORCEPROP 2 LAST CDS_LIB mstr_standard
J 2
(-5925 4075);
DISPLAY 0.723404 (-5925 4075);
PAINT MONO (-5925 4075);
DISPLAY INVISIBLE (-5925 4075);
FORCEPROP 1 LAST BODY_TYPE PLUMBING
J 2
(-5925 4125);
DISPLAY 0.872340 (-5925 4125);
PAINT GREEN (-5925 4125);
DISPLAY INVISIBLE (-5925 4125);
FORCEPROP 1 LAST HDL_TAP TRUE
J 2
(-6250 3950);
DISPLAY 0.872340 (-6250 3950);
DISPLAY INVISIBLE (-6250 3950);
FORCEPROP 1 LAST PATH I295
J 2
(-5923 4075);
DISPLAY 0.872340 (-5923 4075);
PAINT GREEN (-5923 4075);
DISPLAY INVISIBLE (-5923 4075);
FORCEADD TAP..1
R 2
(-5925 3925);
FORCEPROP 3 LASTPIN (-5875 3925) SIG_NAME M_A_CPU1_SA_CA<0>
J 0
(-5865 3935);
DISPLAY 0.659574 (-5865 3935);
PAINT MONO (-5865 3935);
DISPLAY INVISIBLE (-5865 3935);
FORCEPROP 1 LASTPIN (-5875 3925) BN 0
J 2
(-5863 3933);
DISPLAY 0.489362 (-5863 3933);
PAINT GREEN (-5863 3933);
FORCEPROP 2 LAST CDS_LIB mstr_standard
J 0
(-5925 3925);
DISPLAY 0.723404 (-5925 3925);
PAINT MONO (-5925 3925);
DISPLAY INVISIBLE (-5925 3925);
FORCEPROP 1 LAST BODY_TYPE PLUMBING
J 2
(-5925 3975);
DISPLAY 0.872340 (-5925 3975);
PAINT GREEN (-5925 3975);
DISPLAY INVISIBLE (-5925 3975);
FORCEPROP 1 LAST HDL_TAP TRUE
J 2
(-6250 3800);
DISPLAY 0.872340 (-6250 3800);
DISPLAY INVISIBLE (-6250 3800);
FORCEPROP 1 LAST PATH I296
J 2
(-5923 3925);
DISPLAY 0.872340 (-5923 3925);
PAINT GREEN (-5923 3925);
DISPLAY INVISIBLE (-5923 3925);
FORCEADD TAP..1
R 2
(-5925 3875);
FORCEPROP 3 LASTPIN (-5875 3875) SIG_NAME M_A_CPU1_SA_CA<1>
J 0
(-5865 3885);
DISPLAY 0.659574 (-5865 3885);
PAINT MONO (-5865 3885);
DISPLAY INVISIBLE (-5865 3885);
FORCEPROP 1 LASTPIN (-5875 3875) BN 1
J 2
(-5863 3883);
DISPLAY 0.489362 (-5863 3883);
PAINT GREEN (-5863 3883);
FORCEPROP 2 LAST CDS_LIB mstr_standard
J 0
(-5925 3875);
DISPLAY 0.723404 (-5925 3875);
PAINT MONO (-5925 3875);
DISPLAY INVISIBLE (-5925 3875);
FORCEPROP 1 LAST BODY_TYPE PLUMBING
J 2
(-5925 3925);
DISPLAY 0.872340 (-5925 3925);
PAINT GREEN (-5925 3925);
DISPLAY INVISIBLE (-5925 3925);
FORCEPROP 1 LAST HDL_TAP TRUE
J 2
(-6250 3750);
DISPLAY 0.872340 (-6250 3750);
DISPLAY INVISIBLE (-6250 3750);
FORCEPROP 1 LAST PATH I297
J 2
(-5923 3875);
DISPLAY 0.872340 (-5923 3875);
PAINT GREEN (-5923 3875);
DISPLAY INVISIBLE (-5923 3875);
FORCEADD TAP..1
R 2
(-5925 3825);
FORCEPROP 3 LASTPIN (-5875 3825) SIG_NAME M_A_CPU1_SA_CA<2>
J 0
(-5865 3835);
DISPLAY 0.659574 (-5865 3835);
PAINT MONO (-5865 3835);
DISPLAY INVISIBLE (-5865 3835);
FORCEPROP 1 LASTPIN (-5875 3825) BN 2
J 2
(-5863 3833);
DISPLAY 0.489362 (-5863 3833);
PAINT GREEN (-5863 3833);
FORCEPROP 2 LAST CDS_LIB mstr_standard
J 0
(-5925 3825);
DISPLAY 0.723404 (-5925 3825);
PAINT MONO (-5925 3825);
DISPLAY INVISIBLE (-5925 3825);
FORCEPROP 1 LAST BODY_TYPE PLUMBING
J 2
(-5925 3875);
DISPLAY 0.872340 (-5925 3875);
PAINT GREEN (-5925 3875);
DISPLAY INVISIBLE (-5925 3875);
FORCEPROP 1 LAST HDL_TAP TRUE
J 2
(-6250 3700);
DISPLAY 0.872340 (-6250 3700);
DISPLAY INVISIBLE (-6250 3700);
FORCEPROP 1 LAST PATH I298
J 2
(-5923 3825);
DISPLAY 0.872340 (-5923 3825);
PAINT GREEN (-5923 3825);
DISPLAY INVISIBLE (-5923 3825);
FORCEADD TAP..1
R 2
(-5925 3775);
FORCEPROP 3 LASTPIN (-5875 3775) SIG_NAME M_A_CPU1_SA_CA<3>
J 0
(-5865 3785);
DISPLAY 0.659574 (-5865 3785);
PAINT MONO (-5865 3785);
DISPLAY INVISIBLE (-5865 3785);
FORCEPROP 1 LASTPIN (-5875 3775) BN 3
J 2
(-5863 3783);
DISPLAY 0.489362 (-5863 3783);
PAINT GREEN (-5863 3783);
FORCEPROP 2 LAST CDS_LIB mstr_standard
J 0
(-5925 3775);
DISPLAY 0.723404 (-5925 3775);
PAINT MONO (-5925 3775);
DISPLAY INVISIBLE (-5925 3775);
FORCEPROP 1 LAST BODY_TYPE PLUMBING
J 2
(-5925 3825);
DISPLAY 0.872340 (-5925 3825);
PAINT GREEN (-5925 3825);
DISPLAY INVISIBLE (-5925 3825);
FORCEPROP 1 LAST HDL_TAP TRUE
J 2
(-6250 3650);
DISPLAY 0.872340 (-6250 3650);
DISPLAY INVISIBLE (-6250 3650);
FORCEPROP 1 LAST PATH I299
J 2
(-5923 3775);
DISPLAY 0.872340 (-5923 3775);
PAINT GREEN (-5923 3775);
DISPLAY INVISIBLE (-5923 3775);
FORCEADD TAP..1
R 2
(-5925 3725);
FORCEPROP 3 LASTPIN (-5875 3725) SIG_NAME M_A_CPU1_SA_CA<4>
J 0
(-5865 3735);
DISPLAY 0.659574 (-5865 3735);
PAINT MONO (-5865 3735);
DISPLAY INVISIBLE (-5865 3735);
FORCEPROP 1 LASTPIN (-5875 3725) BN 4
J 2
(-5863 3733);
DISPLAY 0.489362 (-5863 3733);
PAINT GREEN (-5863 3733);
FORCEPROP 2 LAST CDS_LIB mstr_standard
J 0
(-5925 3725);
DISPLAY 0.723404 (-5925 3725);
PAINT MONO (-5925 3725);
DISPLAY INVISIBLE (-5925 3725);
FORCEPROP 1 LAST BODY_TYPE PLUMBING
J 2
(-5925 3775);
DISPLAY 0.872340 (-5925 3775);
PAINT GREEN (-5925 3775);
DISPLAY INVISIBLE (-5925 3775);
FORCEPROP 1 LAST HDL_TAP TRUE
J 2
(-6250 3600);
DISPLAY 0.872340 (-6250 3600);
DISPLAY INVISIBLE (-6250 3600);
FORCEPROP 1 LAST PATH I300
J 2
(-5923 3725);
DISPLAY 0.872340 (-5923 3725);
PAINT GREEN (-5923 3725);
DISPLAY INVISIBLE (-5923 3725);
FORCEADD TAP..1
R 2
(-5925 3675);
FORCEPROP 3 LASTPIN (-5875 3675) SIG_NAME M_A_CPU1_SA_CA<5>
J 0
(-5865 3685);
DISPLAY 0.659574 (-5865 3685);
PAINT MONO (-5865 3685);
DISPLAY INVISIBLE (-5865 3685);
FORCEPROP 1 LASTPIN (-5875 3675) BN 5
J 2
(-5863 3683);
DISPLAY 0.489362 (-5863 3683);
PAINT GREEN (-5863 3683);
FORCEPROP 2 LAST CDS_LIB mstr_standard
J 0
(-5925 3675);
DISPLAY 0.723404 (-5925 3675);
PAINT MONO (-5925 3675);
DISPLAY INVISIBLE (-5925 3675);
FORCEPROP 1 LAST BODY_TYPE PLUMBING
J 2
(-5925 3725);
DISPLAY 0.872340 (-5925 3725);
PAINT GREEN (-5925 3725);
DISPLAY INVISIBLE (-5925 3725);
FORCEPROP 1 LAST HDL_TAP TRUE
J 2
(-6250 3550);
DISPLAY 0.872340 (-6250 3550);
DISPLAY INVISIBLE (-6250 3550);
FORCEPROP 1 LAST PATH I301
J 2
(-5923 3675);
DISPLAY 0.872340 (-5923 3675);
PAINT GREEN (-5923 3675);
DISPLAY INVISIBLE (-5923 3675);
FORCEADD TAP..1
R 2
(-5925 3625);
FORCEPROP 3 LASTPIN (-5875 3625) SIG_NAME M_A_CPU1_SA_CA<6>
J 0
(-5865 3635);
DISPLAY 0.659574 (-5865 3635);
PAINT MONO (-5865 3635);
DISPLAY INVISIBLE (-5865 3635);
FORCEPROP 1 LASTPIN (-5875 3625) BN 6
J 2
(-5863 3633);
DISPLAY 0.489362 (-5863 3633);
PAINT GREEN (-5863 3633);
FORCEPROP 2 LAST CDS_LIB mstr_standard
J 0
(-5925 3625);
DISPLAY 0.723404 (-5925 3625);
PAINT MONO (-5925 3625);
DISPLAY INVISIBLE (-5925 3625);
FORCEPROP 1 LAST BODY_TYPE PLUMBING
J 2
(-5925 3675);
DISPLAY 0.872340 (-5925 3675);
PAINT GREEN (-5925 3675);
DISPLAY INVISIBLE (-5925 3675);
FORCEPROP 1 LAST HDL_TAP TRUE
J 2
(-6250 3500);
DISPLAY 0.872340 (-6250 3500);
DISPLAY INVISIBLE (-6250 3500);
FORCEPROP 1 LAST PATH I302
J 2
(-5923 3625);
DISPLAY 0.872340 (-5923 3625);
PAINT GREEN (-5923 3625);
DISPLAY INVISIBLE (-5923 3625);
FORCEADD TAP..1
R 2
(-5925 3475);
FORCEPROP 3 LASTPIN (-5875 3475) SIG_NAME M_A_CPU1_SB_CA<1>
J 0
(-5865 3485);
DISPLAY 0.659574 (-5865 3485);
PAINT MONO (-5865 3485);
DISPLAY INVISIBLE (-5865 3485);
FORCEPROP 1 LASTPIN (-5875 3475) BN 1
J 2
(-5863 3483);
DISPLAY 0.489362 (-5863 3483);
PAINT GREEN (-5863 3483);
FORCEPROP 2 LAST CDS_LIB mstr_standard
J 0
(-5925 3475);
DISPLAY 0.723404 (-5925 3475);
PAINT MONO (-5925 3475);
DISPLAY INVISIBLE (-5925 3475);
FORCEPROP 1 LAST BODY_TYPE PLUMBING
J 2
(-5925 3525);
DISPLAY 0.872340 (-5925 3525);
PAINT GREEN (-5925 3525);
DISPLAY INVISIBLE (-5925 3525);
FORCEPROP 1 LAST HDL_TAP TRUE
J 2
(-6250 3350);
DISPLAY 0.872340 (-6250 3350);
DISPLAY INVISIBLE (-6250 3350);
FORCEPROP 1 LAST PATH I303
J 2
(-5923 3475);
DISPLAY 0.872340 (-5923 3475);
PAINT GREEN (-5923 3475);
DISPLAY INVISIBLE (-5923 3475);
FORCEADD TAP..1
R 2
(-5925 3525);
FORCEPROP 3 LASTPIN (-5875 3525) SIG_NAME M_A_CPU1_SB_CA<0>
J 0
(-5865 3535);
DISPLAY 0.659574 (-5865 3535);
PAINT MONO (-5865 3535);
DISPLAY INVISIBLE (-5865 3535);
FORCEPROP 1 LASTPIN (-5875 3525) BN 0
J 2
(-5863 3533);
DISPLAY 0.489362 (-5863 3533);
PAINT GREEN (-5863 3533);
FORCEPROP 2 LAST CDS_LIB mstr_standard
J 0
(-5925 3525);
DISPLAY 0.723404 (-5925 3525);
PAINT MONO (-5925 3525);
DISPLAY INVISIBLE (-5925 3525);
FORCEPROP 1 LAST BODY_TYPE PLUMBING
J 2
(-5925 3575);
DISPLAY 0.872340 (-5925 3575);
PAINT GREEN (-5925 3575);
DISPLAY INVISIBLE (-5925 3575);
FORCEPROP 1 LAST HDL_TAP TRUE
J 2
(-6250 3400);
DISPLAY 0.872340 (-6250 3400);
DISPLAY INVISIBLE (-6250 3400);
FORCEPROP 1 LAST PATH I304
J 2
(-5923 3525);
DISPLAY 0.872340 (-5923 3525);
PAINT GREEN (-5923 3525);
DISPLAY INVISIBLE (-5923 3525);
FORCEADD TAP..1
R 2
(-5925 3425);
FORCEPROP 3 LASTPIN (-5875 3425) SIG_NAME M_A_CPU1_SB_CA<2>
J 0
(-5865 3435);
DISPLAY 0.659574 (-5865 3435);
PAINT MONO (-5865 3435);
DISPLAY INVISIBLE (-5865 3435);
FORCEPROP 1 LASTPIN (-5875 3425) BN 2
J 2
(-5863 3433);
DISPLAY 0.489362 (-5863 3433);
PAINT GREEN (-5863 3433);
FORCEPROP 2 LAST CDS_LIB mstr_standard
J 0
(-5925 3425);
DISPLAY 0.723404 (-5925 3425);
PAINT MONO (-5925 3425);
DISPLAY INVISIBLE (-5925 3425);
FORCEPROP 1 LAST BODY_TYPE PLUMBING
J 2
(-5925 3475);
DISPLAY 0.872340 (-5925 3475);
PAINT GREEN (-5925 3475);
DISPLAY INVISIBLE (-5925 3475);
FORCEPROP 1 LAST HDL_TAP TRUE
J 2
(-6250 3300);
DISPLAY 0.872340 (-6250 3300);
DISPLAY INVISIBLE (-6250 3300);
FORCEPROP 1 LAST PATH I305
J 2
(-5923 3425);
DISPLAY 0.872340 (-5923 3425);
PAINT GREEN (-5923 3425);
DISPLAY INVISIBLE (-5923 3425);
FORCEADD TAP..1
R 2
(-5925 3375);
FORCEPROP 3 LASTPIN (-5875 3375) SIG_NAME M_A_CPU1_SB_CA<3>
J 0
(-5865 3385);
DISPLAY 0.659574 (-5865 3385);
PAINT MONO (-5865 3385);
DISPLAY INVISIBLE (-5865 3385);
FORCEPROP 1 LASTPIN (-5875 3375) BN 3
J 2
(-5863 3383);
DISPLAY 0.489362 (-5863 3383);
PAINT GREEN (-5863 3383);
FORCEPROP 2 LAST CDS_LIB mstr_standard
J 0
(-5925 3375);
DISPLAY 0.723404 (-5925 3375);
PAINT MONO (-5925 3375);
DISPLAY INVISIBLE (-5925 3375);
FORCEPROP 1 LAST BODY_TYPE PLUMBING
J 2
(-5925 3425);
DISPLAY 0.872340 (-5925 3425);
PAINT GREEN (-5925 3425);
DISPLAY INVISIBLE (-5925 3425);
FORCEPROP 1 LAST HDL_TAP TRUE
J 2
(-6250 3250);
DISPLAY 0.872340 (-6250 3250);
DISPLAY INVISIBLE (-6250 3250);
FORCEPROP 1 LAST PATH I306
J 2
(-5923 3375);
DISPLAY 0.872340 (-5923 3375);
PAINT GREEN (-5923 3375);
DISPLAY INVISIBLE (-5923 3375);
FORCEADD TAP..1
R 2
(-5925 3325);
FORCEPROP 3 LASTPIN (-5875 3325) SIG_NAME M_A_CPU1_SB_CA<4>
J 0
(-5865 3335);
DISPLAY 0.659574 (-5865 3335);
PAINT MONO (-5865 3335);
DISPLAY INVISIBLE (-5865 3335);
FORCEPROP 1 LASTPIN (-5875 3325) BN 4
J 2
(-5863 3333);
DISPLAY 0.489362 (-5863 3333);
PAINT GREEN (-5863 3333);
FORCEPROP 2 LAST CDS_LIB mstr_standard
J 0
(-5925 3325);
DISPLAY 0.723404 (-5925 3325);
PAINT MONO (-5925 3325);
DISPLAY INVISIBLE (-5925 3325);
FORCEPROP 1 LAST BODY_TYPE PLUMBING
J 2
(-5925 3375);
DISPLAY 0.872340 (-5925 3375);
PAINT GREEN (-5925 3375);
DISPLAY INVISIBLE (-5925 3375);
FORCEPROP 1 LAST HDL_TAP TRUE
J 2
(-6250 3200);
DISPLAY 0.872340 (-6250 3200);
DISPLAY INVISIBLE (-6250 3200);
FORCEPROP 1 LAST PATH I307
J 2
(-5923 3325);
DISPLAY 0.872340 (-5923 3325);
PAINT GREEN (-5923 3325);
DISPLAY INVISIBLE (-5923 3325);
FORCEADD TAP..1
R 2
(-5925 3225);
FORCEPROP 3 LASTPIN (-5875 3225) SIG_NAME M_A_CPU1_SB_CA<6>
J 0
(-5865 3235);
DISPLAY 0.659574 (-5865 3235);
PAINT MONO (-5865 3235);
DISPLAY INVISIBLE (-5865 3235);
FORCEPROP 1 LASTPIN (-5875 3225) BN 6
J 2
(-5863 3233);
DISPLAY 0.489362 (-5863 3233);
PAINT GREEN (-5863 3233);
FORCEPROP 2 LAST CDS_LIB mstr_standard
J 0
(-5925 3225);
DISPLAY 0.723404 (-5925 3225);
PAINT MONO (-5925 3225);
DISPLAY INVISIBLE (-5925 3225);
FORCEPROP 1 LAST BODY_TYPE PLUMBING
J 2
(-5925 3275);
DISPLAY 0.872340 (-5925 3275);
PAINT GREEN (-5925 3275);
DISPLAY INVISIBLE (-5925 3275);
FORCEPROP 1 LAST HDL_TAP TRUE
J 2
(-6250 3100);
DISPLAY 0.872340 (-6250 3100);
DISPLAY INVISIBLE (-6250 3100);
FORCEPROP 1 LAST PATH I308
J 2
(-5923 3225);
DISPLAY 0.872340 (-5923 3225);
PAINT GREEN (-5923 3225);
DISPLAY INVISIBLE (-5923 3225);
FORCEADD TAP..1
R 2
(-5925 3275);
FORCEPROP 3 LASTPIN (-5875 3275) SIG_NAME M_A_CPU1_SB_CA<5>
J 0
(-5865 3285);
DISPLAY 0.659574 (-5865 3285);
PAINT MONO (-5865 3285);
DISPLAY INVISIBLE (-5865 3285);
FORCEPROP 1 LASTPIN (-5875 3275) BN 5
J 2
(-5863 3283);
DISPLAY 0.489362 (-5863 3283);
PAINT GREEN (-5863 3283);
FORCEPROP 2 LAST CDS_LIB mstr_standard
J 0
(-5925 3275);
DISPLAY 0.723404 (-5925 3275);
PAINT MONO (-5925 3275);
DISPLAY INVISIBLE (-5925 3275);
FORCEPROP 1 LAST BODY_TYPE PLUMBING
J 2
(-5925 3325);
DISPLAY 0.872340 (-5925 3325);
PAINT GREEN (-5925 3325);
DISPLAY INVISIBLE (-5925 3325);
FORCEPROP 1 LAST HDL_TAP TRUE
J 2
(-6250 3150);
DISPLAY 0.872340 (-6250 3150);
DISPLAY INVISIBLE (-6250 3150);
FORCEPROP 1 LAST PATH I309
J 2
(-5923 3275);
DISPLAY 0.872340 (-5923 3275);
PAINT GREEN (-5923 3275);
DISPLAY INVISIBLE (-5923 3275);
FORCEADD OFFPAGE..2
R 2
(-6525 3950);
FORCEPROP 2 LAST $XR0 97 
J 0
(-6749 3950);
DISPLAY 0.638298 (-6749 3950);
PAINT MONO (-6749 3950);
FORCEPROP 2 LAST PATH I310
J 0
(-6775 4000);
DISPLAY 1.021277 (-6775 4000);
DISPLAY INVISIBLE (-6775 4000);
FORCEPROP 1 LAST COMMENT_BODY TRUE
J 2
(-6480 3855);
DISPLAY 0.872340 (-6480 3855);
PAINT GREEN (-6480 3855);
DISPLAY INVISIBLE (-6480 3855);
FORCEPROP 1 LAST OFFPAGE TRUE
J 2
(-6850 3825);
DISPLAY 0.872340 (-6850 3825);
PAINT GREEN (-6850 3825);
DISPLAY INVISIBLE (-6850 3825);
FORCEPROP 2 LAST CDS_LIB standard
J 0
(-6525 3950);
DISPLAY INVISIBLE (-6525 3950);
FORCEADD OFFPAGE..2
R 2
(-6525 3550);
FORCEPROP 2 LAST $XR0 97 
J 0
(-6749 3550);
DISPLAY 0.638298 (-6749 3550);
PAINT MONO (-6749 3550);
FORCEPROP 2 LAST PATH I311
J 0
(-6775 3600);
DISPLAY 1.021277 (-6775 3600);
DISPLAY INVISIBLE (-6775 3600);
FORCEPROP 1 LAST COMMENT_BODY TRUE
J 2
(-6480 3455);
DISPLAY 0.872340 (-6480 3455);
PAINT GREEN (-6480 3455);
DISPLAY INVISIBLE (-6480 3455);
FORCEPROP 1 LAST OFFPAGE TRUE
J 2
(-6850 3425);
DISPLAY 0.872340 (-6850 3425);
PAINT GREEN (-6850 3425);
DISPLAY INVISIBLE (-6850 3425);
FORCEPROP 2 LAST CDS_LIB standard
J 0
(-6525 3550);
DISPLAY INVISIBLE (-6525 3550);
FORCEADD OFFPAGE..2
R 2
(-6525 3075);
FORCEPROP 2 LAST $XR0 97 
J 0
(-6749 3075);
DISPLAY 0.638298 (-6749 3075);
PAINT MONO (-6749 3075);
FORCEPROP 2 LAST PATH I312
J 0
(-6775 3125);
DISPLAY 1.021277 (-6775 3125);
DISPLAY INVISIBLE (-6775 3125);
FORCEPROP 1 LAST COMMENT_BODY TRUE
J 2
(-6480 2980);
DISPLAY 0.872340 (-6480 2980);
PAINT GREEN (-6480 2980);
DISPLAY INVISIBLE (-6480 2980);
FORCEPROP 1 LAST OFFPAGE TRUE
J 2
(-6850 2950);
DISPLAY 0.872340 (-6850 2950);
PAINT GREEN (-6850 2950);
DISPLAY INVISIBLE (-6850 2950);
FORCEPROP 2 LAST CDS_LIB standard
J 0
(-6525 3075);
DISPLAY INVISIBLE (-6525 3075);
FORCEADD OFFPAGE..2
R 2
(-6525 3025);
FORCEPROP 2 LAST $XR0 97 
J 0
(-6749 3025);
DISPLAY 0.638298 (-6749 3025);
PAINT MONO (-6749 3025);
FORCEPROP 2 LAST PATH I313
J 0
(-6775 3075);
DISPLAY 1.021277 (-6775 3075);
DISPLAY INVISIBLE (-6775 3075);
FORCEPROP 1 LAST COMMENT_BODY TRUE
J 2
(-6480 2930);
DISPLAY 0.872340 (-6480 2930);
PAINT GREEN (-6480 2930);
DISPLAY INVISIBLE (-6480 2930);
FORCEPROP 1 LAST OFFPAGE TRUE
J 2
(-6850 2900);
DISPLAY 0.872340 (-6850 2900);
PAINT GREEN (-6850 2900);
DISPLAY INVISIBLE (-6850 2900);
FORCEPROP 2 LAST CDS_LIB standard
J 0
(-6525 3025);
DISPLAY INVISIBLE (-6525 3025);
FORCEADD OFFPAGE..2
R 2
(-6525 2925);
FORCEPROP 2 LAST $XR0 97 
J 0
(-6749 2925);
DISPLAY 0.638298 (-6749 2925);
PAINT MONO (-6749 2925);
FORCEPROP 2 LAST PATH I314
J 0
(-6775 2975);
DISPLAY 1.021277 (-6775 2975);
DISPLAY INVISIBLE (-6775 2975);
FORCEPROP 1 LAST COMMENT_BODY TRUE
J 2
(-6480 2830);
DISPLAY 0.872340 (-6480 2830);
PAINT GREEN (-6480 2830);
DISPLAY INVISIBLE (-6480 2830);
FORCEPROP 1 LAST OFFPAGE TRUE
J 2
(-6850 2800);
DISPLAY 0.872340 (-6850 2800);
PAINT GREEN (-6850 2800);
DISPLAY INVISIBLE (-6850 2800);
FORCEPROP 2 LAST CDS_LIB standard
J 0
(-6525 2925);
DISPLAY INVISIBLE (-6525 2925);
FORCEADD OFFPAGE..2
R 2
(-6525 2875);
FORCEPROP 2 LAST $XR0 97 
J 0
(-6749 2875);
DISPLAY 0.638298 (-6749 2875);
PAINT MONO (-6749 2875);
FORCEPROP 2 LAST PATH I315
J 0
(-6775 2925);
DISPLAY 1.021277 (-6775 2925);
DISPLAY INVISIBLE (-6775 2925);
FORCEPROP 1 LAST COMMENT_BODY TRUE
J 2
(-6480 2780);
DISPLAY 0.872340 (-6480 2780);
PAINT GREEN (-6480 2780);
DISPLAY INVISIBLE (-6480 2780);
FORCEPROP 1 LAST OFFPAGE TRUE
J 2
(-6850 2750);
DISPLAY 0.872340 (-6850 2750);
PAINT GREEN (-6850 2750);
DISPLAY INVISIBLE (-6850 2750);
FORCEPROP 2 LAST CDS_LIB standard
J 0
(-6525 2875);
DISPLAY INVISIBLE (-6525 2875);
FORCEADD OFFPAGE..1
(-6525 2775);
FORCEPROP 2 LAST $XR0 97 
J 0
(-6746 2775);
DISPLAY 0.638298 (-6746 2775);
PAINT MONO (-6746 2775);
FORCEPROP 2 LAST PATH I316
J 0
(-6775 2825);
DISPLAY 1.021277 (-6775 2825);
DISPLAY INVISIBLE (-6775 2825);
FORCEPROP 1 LAST COMMENT_BODY TRUE
J 0
(-6400 2675);
DISPLAY 0.872340 (-6400 2675);
PAINT GREEN (-6400 2675);
DISPLAY INVISIBLE (-6400 2675);
FORCEPROP 1 LAST OFFPAGE TRUE
J 0
(-6200 2650);
DISPLAY 0.872340 (-6200 2650);
PAINT GREEN (-6200 2650);
DISPLAY INVISIBLE (-6200 2650);
FORCEPROP 2 LAST CDS_LIB standard
J 0
(-6525 2775);
DISPLAY INVISIBLE (-6525 2775);
FORCEADD OFFPAGE..5
(-6525 2675);
FORCEPROP 2 LAST $XR0 97 
J 0
(-6749 2675);
DISPLAY 0.638298 (-6749 2675);
PAINT MONO (-6749 2675);
FORCEPROP 2 LAST PATH I317
J 0
(-6775 2725);
DISPLAY 1.021277 (-6775 2725);
DISPLAY INVISIBLE (-6775 2725);
FORCEPROP 1 LAST COMMENT_BODY TRUE
J 0
(-6425 2600);
DISPLAY 0.872340 (-6425 2600);
PAINT GREEN (-6425 2600);
DISPLAY INVISIBLE (-6425 2600);
FORCEPROP 1 LAST OFFPAGE TRUE
J 0
(-6200 2550);
DISPLAY 0.872340 (-6200 2550);
PAINT GREEN (-6200 2550);
DISPLAY INVISIBLE (-6200 2550);
FORCEPROP 2 LAST CDS_LIB mstr_standard
J 0
(-6525 2675);
DISPLAY INVISIBLE (-6525 2675);
FORCEADD OFFPAGE..2
R 2
(-6525 2575);
FORCEPROP 2 LAST $XR0 97 
J 0
(-6749 2575);
DISPLAY 0.638298 (-6749 2575);
PAINT MONO (-6749 2575);
FORCEPROP 2 LAST PATH I318
J 0
(-6775 2625);
DISPLAY 1.021277 (-6775 2625);
DISPLAY INVISIBLE (-6775 2625);
FORCEPROP 1 LAST COMMENT_BODY TRUE
J 2
(-6480 2480);
DISPLAY 0.872340 (-6480 2480);
PAINT GREEN (-6480 2480);
DISPLAY INVISIBLE (-6480 2480);
FORCEPROP 1 LAST OFFPAGE TRUE
J 2
(-6850 2450);
DISPLAY 0.872340 (-6850 2450);
PAINT GREEN (-6850 2450);
DISPLAY INVISIBLE (-6850 2450);
FORCEPROP 2 LAST CDS_LIB standard
J 0
(-6525 2575);
DISPLAY INVISIBLE (-6525 2575);
FORCEADD OFFPAGE..2
R 2
(-6525 2525);
FORCEPROP 2 LAST $XR0 97 
J 0
(-6749 2525);
DISPLAY 0.638298 (-6749 2525);
PAINT MONO (-6749 2525);
FORCEPROP 2 LAST PATH I319
J 0
(-6775 2575);
DISPLAY 1.021277 (-6775 2575);
DISPLAY INVISIBLE (-6775 2575);
FORCEPROP 1 LAST COMMENT_BODY TRUE
J 2
(-6480 2430);
DISPLAY 0.872340 (-6480 2430);
PAINT GREEN (-6480 2430);
DISPLAY INVISIBLE (-6480 2430);
FORCEPROP 1 LAST OFFPAGE TRUE
J 2
(-6850 2400);
DISPLAY 0.872340 (-6850 2400);
PAINT GREEN (-6850 2400);
DISPLAY INVISIBLE (-6850 2400);
FORCEPROP 2 LAST CDS_LIB standard
J 0
(-6525 2525);
DISPLAY INVISIBLE (-6525 2525);
FORCEADD OFFPAGE..1
(-6525 2425);
FORCEPROP 2 LAST $XR0 97 
J 0
(-6746 2425);
DISPLAY 0.638298 (-6746 2425);
PAINT MONO (-6746 2425);
FORCEPROP 2 LAST PATH I320
J 0
(-6775 2475);
DISPLAY 1.021277 (-6775 2475);
DISPLAY INVISIBLE (-6775 2475);
FORCEPROP 1 LAST COMMENT_BODY TRUE
J 0
(-6400 2325);
DISPLAY 0.872340 (-6400 2325);
PAINT GREEN (-6400 2325);
DISPLAY INVISIBLE (-6400 2325);
FORCEPROP 1 LAST OFFPAGE TRUE
J 0
(-6200 2300);
DISPLAY 0.872340 (-6200 2300);
PAINT GREEN (-6200 2300);
DISPLAY INVISIBLE (-6200 2300);
FORCEPROP 2 LAST CDS_LIB standard
J 0
(-6525 2425);
DISPLAY INVISIBLE (-6525 2425);
FORCEADD OFFPAGE..5
(-6525 2325);
FORCEPROP 2 LAST $XR0 97 
J 0
(-6749 2325);
DISPLAY 0.638298 (-6749 2325);
PAINT MONO (-6749 2325);
FORCEPROP 2 LAST PATH I321
J 0
(-6775 2375);
DISPLAY 1.021277 (-6775 2375);
DISPLAY INVISIBLE (-6775 2375);
FORCEPROP 1 LAST COMMENT_BODY TRUE
J 0
(-6425 2250);
DISPLAY 0.872340 (-6425 2250);
PAINT GREEN (-6425 2250);
DISPLAY INVISIBLE (-6425 2250);
FORCEPROP 1 LAST OFFPAGE TRUE
J 0
(-6200 2200);
DISPLAY 0.872340 (-6200 2200);
PAINT GREEN (-6200 2200);
DISPLAY INVISIBLE (-6200 2200);
FORCEPROP 2 LAST CDS_LIB standard
J 0
(-6525 2325);
DISPLAY INVISIBLE (-6525 2325);
FORCEADD Q_RES..1
(-6600 2225);
FORCEPROP 1 LAST LOCATION R500
J 0
(-6925 2225);
DISPLAY 0.489362 (-6925 2225);
PAINT SKYBLUE (-6925 2225);
FORCEPROP 0 LAST $SEC 1
J 0
(-6775 2275);
DISPLAY 0.680851 (-6775 2275);
PAINT MONO (-6775 2275);
DISPLAY INVISIBLE (-6775 2275);
FORCEPROP 0 LAST CDS_SEC 1
J 0
(-6775 2275);
DISPLAY 1.021277 (-6775 2275);
DISPLAY INVISIBLE (-6775 2275);
FORCEPROP 1 LASTPIN (-6700 2225) $PN 1
J 0
(-6688 2237);
DISPLAY 0.489362 (-6688 2237);
PAINT MONO (-6688 2237);
FORCEPROP 1 LASTPIN (-6500 2225) $PN 2
J 0
(-6538 2237);
DISPLAY 0.489362 (-6538 2237);
PAINT MONO (-6538 2237);
FORCEPROP 1 LAST TOLERANCE 1%
J 0
(-6325 2225);
DISPLAY 0.489362 (-6325 2225);
PAINT SKYBLUE (-6325 2225);
FORCEPROP 1 LAST VALUE 15   
J 2
(-6275 2225);
DISPLAY 0.489362 (-6275 2225);
PAINT SKYBLUE (-6275 2225);
FORCEPROP 1 LAST PART_NUMBER CS01502FB11
J 0
(-6450 2200);
DISPLAY 0.489362 (-6450 2200);
PAINT SKYBLUE (-6450 2200);
FORCEPROP 1 LAST PACK_TYPE 0402LF
J 0
(-6925 2200);
DISPLAY 0.489362 (-6925 2200);
PAINT SKYBLUE (-6925 2200);
FORCEPROP 2 LAST CDS_LIB pure_quanta
J 0
(-6600 2225);
DISPLAY INVISIBLE (-6600 2225);
FORCEPROP 1 LAST PATH I322
J 0
(-6650 2375);
DISPLAY 0.978723 (-6650 2375);
PAINT WHITE (-6650 2375);
DISPLAY INVISIBLE (-6650 2375);
FORCEPROP 1 LAST WATTAGE 1/16W
J 2
(-6375 2350);
DISPLAY 0.638298 (-6375 2350);
PAINT SKYBLUE (-6375 2350);
DISPLAY INVISIBLE (-6375 2350);
FORCEPROP 1 LAST MATERIAL CHIP
J 0
(-6725 2350);
DISPLAY 0.638298 (-6725 2350);
PAINT SKYBLUE (-6725 2350);
DISPLAY INVISIBLE (-6725 2350);
FORCEADD OFFPAGE..5
(-6525 2125);
FORCEPROP 2 LAST $XR0 97 
J 0
(-6749 2125);
DISPLAY 0.638298 (-6749 2125);
PAINT MONO (-6749 2125);
FORCEPROP 2 LAST PATH I323
J 0
(-6775 2175);
DISPLAY 1.021277 (-6775 2175);
DISPLAY INVISIBLE (-6775 2175);
FORCEPROP 1 LAST COMMENT_BODY TRUE
J 0
(-6425 2050);
DISPLAY 0.872340 (-6425 2050);
PAINT GREEN (-6425 2050);
DISPLAY INVISIBLE (-6425 2050);
FORCEPROP 1 LAST OFFPAGE TRUE
J 0
(-6200 2000);
DISPLAY 0.872340 (-6200 2000);
PAINT GREEN (-6200 2000);
DISPLAY INVISIBLE (-6200 2000);
FORCEPROP 2 LAST CDS_LIB standard
J 0
(-6525 2125);
DISPLAY INVISIBLE (-6525 2125);
FORCEADD OFFPAGE..1
(-7475 2225);
FORCEPROP 2 LAST $XR0 97 
J 0
(-7726 2225);
DISPLAY 0.638298 (-7726 2225);
PAINT MONO (-7726 2225);
FORCEPROP 2 LAST PATH I324
J 0
(-7725 2275);
DISPLAY 1.021277 (-7725 2275);
DISPLAY INVISIBLE (-7725 2275);
FORCEPROP 1 LAST COMMENT_BODY TRUE
J 0
(-7350 2125);
DISPLAY 0.872340 (-7350 2125);
PAINT GREEN (-7350 2125);
DISPLAY INVISIBLE (-7350 2125);
FORCEPROP 1 LAST OFFPAGE TRUE
J 0
(-7150 2100);
DISPLAY 0.872340 (-7150 2100);
PAINT GREEN (-7150 2100);
DISPLAY INVISIBLE (-7150 2100);
FORCEPROP 2 LAST CDS_LIB mstr_standard
J 0
(-7475 2225);
DISPLAY INVISIBLE (-7475 2225);
FORCEADD CAD_NOTE..1
(-7675 2525);
FORCEPROP 0 LAST L1 R1958 PLACE CLOSE TO CPU < 25MM
J 0
(-7825 2400);
DISPLAY 0.617021 (-7825 2400);
PAINT WHITE (-7825 2400);
FORCEPROP 2 LAST CDS_LIB pure_quanta_power
J 0
(-7675 2525);
DISPLAY INVISIBLE (-7675 2525);
FORCEPROP 1 LAST COMMENT_BODY TRUE
J 0
(-7650 2625);
DISPLAY 0.574468 (-7650 2625);
PAINT WHITE (-7650 2625);
DISPLAY INVISIBLE (-7650 2625);
FORCEADD QUANTA_TITLE_BLOCK_C..1
(-100 100);
FORCEPROP 0 LAST CDS_CON_LAST_MODIFIED Fri Mar 11 14:52:29 2022
J 0
(-1985 115);
DISPLAY INVISIBLE (-1985 115);
FORCEPROP 1 LAST CUSTOM_TXT_CDS <CON_LAST_MODIFIED>
J 0
(-1985 115);
DISPLAY 0.978723 (-1985 115);
FORCEPROP 2 LAST CUSTOM_TXT_CDS <XR_PAGE_TITLE>
J 0
(-7990 5350);
DISPLAY 0.638298 (-7990 5350);
PAINT PINK (-7990 5350);
DISPLAY INVISIBLE (-7990 5350);
FORCEPROP 1 LAST CUSTOM_TXT_CDS <NAME_2>
J 0
(-3275 150);
FORCEPROP 1 LAST CUSTOM_TXT_CDS <NAME_1>
J 0
(-3275 275);
FORCEPROP 1 LAST CUSTOM_TXT_CDS <Q_NUMBER>
J 0
(-1503 203);
DISPLAY 1.212766 (-1503 203);
FORCEPROP 1 LAST CUSTOM_TXT_CDS <Q_PROJ>
J 0
(-2482 202);
DISPLAY 1.212766 (-2482 202);
FORCEPROP 1 LAST CUSTOM_TXT_CDS <Q_REV>
J 0
(-284 203);
DISPLAY 1.212766 (-284 203);
FORCEPROP 1 LAST CUSTOM_TXT_CDS <CON_PAGE_NUM> OF <CON_TOTAL_PAGES>
J 0
(-546 118);
DISPLAY 0.978723 (-546 118);
FORCEPROP 1 LAST Q_TITLE CPU1 DDR CHA
J 0
(-9400 175);
DISPLAY 2.446809 (-9400 175);
PAINT GREEN (-9400 175);
FORCEPROP 1 LAST Q_DEPT BU9
J 1
(-3863 149);
DISPLAY 1.957447 (-3863 149);
PAINT GREEN (-3863 149);
FORCEPROP 2 LAST PAGE_BORDER TRUE
J 0
(-7990 5350);
DISPLAY 0.638298 (-7990 5350);
PAINT PINK (-7990 5350);
DISPLAY INVISIBLE (-7990 5350);
FORCEPROP 1 LAST CDS_LMAN_SYM_OUTLINE -9475,6775,100,-125
J 0
(-100 100);
DISPLAY 0.468085 (-100 100);
PAINT GREEN (-100 100);
DISPLAY INVISIBLE (-100 100);
FORCEPROP 2 LAST CDS_LIB pure_quanta
J 0
(-100 100);
DISPLAY INVISIBLE (-100 100);
FORCEPROP 1 LAST COMMENT_BODY TRUE
J 0
(-88 87);
DISPLAY 0.978723 (-88 87);
PAINT GREEN (-88 87);
DISPLAY INVISIBLE (-88 87);
FORCEPROP 2 LAST CDS_XR_PAGE_TITLE CR-37 : @T6G_MB_LIB.T6G(SCH_1):PAGE37
J 0
(-7990 5350);
DISPLAY 0.638298 (-7990 5350);
PAINT PINK (-7990 5350);
DISPLAY INVISIBLE (-7990 5350);
WIRE 17 -1 (-3250 5900)(-3250 5850);
WIRE 17 -1 (-3250 5950)(-3250 5900);
WIRE 17 -1 (-3250 5850)(-3250 5800);
WIRE 17 -1 (-3250 5800)(-3250 5750);
WIRE 17 -1 (-3250 6000)(-3250 5950);
WIRE 17 -1 (-3250 6050)(-3250 6000);
WIRE 17 -1 (-3250 5750)(-3250 5650);
WIRE 17 -1 (-3250 5650)(-3250 5600);
WIRE 17 -1 (-3250 6100)(-3250 6050);
WIRE 17 -1 (-3250 6100)(-2625 6100);
FORCEPROP 2 LAST SIG_NAME M_A_CPU1_SA_DQ<31:0>
J 2
(-2685 6110);
DISPLAY 0.489362 (-2685 6110);
WIRE 17 -1 (-3250 5600)(-3250 5550);
WIRE 17 -1 (-3250 5550)(-3250 5500);
WIRE 17 -1 (-3250 5500)(-3250 5450);
WIRE 17 -1 (-3250 5450)(-3250 5400);
WIRE 17 -1 (-3250 5400)(-3250 5350);
WIRE 17 -1 (-3250 5350)(-3250 5300);
WIRE 17 -1 (-3250 5200)(-3250 5300);
WIRE 17 -1 (-3250 5150)(-3250 5200);
WIRE 17 -1 (-3250 5100)(-3250 5150);
WIRE 17 -1 (-3250 5050)(-3250 5100);
WIRE 17 -1 (-3250 5050)(-3250 5000);
WIRE 17 -1 (-3250 5000)(-3250 4950);
WIRE 17 -1 (-3250 4950)(-3250 4900);
WIRE 17 -1 (-3250 4900)(-3250 4850);
WIRE 17 -1 (-3250 4850)(-3250 4750);
WIRE 17 -1 (-3250 4750)(-3250 4700);
WIRE 17 -1 (-3250 4700)(-3250 4650);
WIRE 17 -1 (-3250 4650)(-3250 4600);
WIRE 17 -1 (-3250 4550)(-3250 4600);
WIRE 17 -1 (-3250 4500)(-3250 4550);
WIRE 17 -1 (-3250 4450)(-3250 4500);
WIRE 17 -1 (-3250 4400)(-3250 4450);
WIRE 17 -1 (-3250 4200)(-3250 4150);
WIRE 17 -1 (-3250 4250)(-3250 4200);
WIRE 17 -1 (-3250 4150)(-3250 4100);
WIRE 17 -1 (-3250 4100)(-3250 4050);
WIRE 17 -1 (-3250 4300)(-3250 4250);
WIRE 17 -1 (-3250 4300)(-2625 4300);
FORCEPROP 2 LAST SIG_NAME M_A_CPU1_SB_DQ<31:0>
J 2
(-2685 4310);
DISPLAY 0.489362 (-2685 4310);
WIRE 17 -1 (-3250 3250)(-3250 3300);
WIRE 17 -1 (-3250 3250)(-3250 3200);
WIRE 17 -1 (-3250 3300)(-3250 3350);
WIRE 17 -1 (-3250 3350)(-3250 3400);
WIRE 17 -1 (-3250 3200)(-3250 3150);
WIRE 17 -1 (-3250 3150)(-3250 3100);
WIRE 17 -1 (-3250 3400)(-3250 3500);
WIRE 17 -1 (-3250 3550)(-3250 3500);
WIRE 17 -1 (-3250 3100)(-3250 3050);
WIRE 17 -1 (-3250 3050)(-3250 2950);
WIRE 17 -1 (-3250 3600)(-3250 3550);
WIRE 17 -1 (-3250 3650)(-3250 3600);
WIRE 17 -1 (-3250 2950)(-3250 2900);
WIRE 17 -1 (-3250 2900)(-3250 2850);
WIRE 17 -1 (-3250 3700)(-3250 3650);
WIRE 17 -1 (-3250 3750)(-3250 3700);
WIRE 17 -1 (-3250 2850)(-3250 2800);
WIRE 17 -1 (-3250 2750)(-3250 2800);
WIRE 17 -1 (-3250 3800)(-3250 3750);
WIRE 17 -1 (-3250 3850)(-3250 3800);
WIRE 17 -1 (-3250 2700)(-3250 2750);
WIRE 17 -1 (-3250 2650)(-3250 2700);
WIRE 17 -1 (-3250 3950)(-3250 3850);
WIRE 17 -1 (-3250 4000)(-3250 3950);
WIRE 17 -1 (-3250 2600)(-3250 2650);
WIRE 17 -1 (-3250 4050)(-3250 4000);
WIRE 17 -1 (-3250 2500)(-3250 2525);
WIRE 17 -1 (-3250 2500)(-3250 2450);
WIRE 17 -1 (-3250 2525)(-2750 2525);
FORCEPROP 2 LAST SIG_NAME M_A_CPU1_SA_CB<7:0>
J 2
(-2750 2535);
DISPLAY 0.489362 (-2750 2535);
WIRE 17 -1 (-3250 2400)(-3250 2450);
WIRE 17 -1 (-3250 2400)(-3250 2350);
WIRE 17 -1 (-3250 2300)(-3250 2350);
WIRE 17 -1 (-3250 2250)(-3250 2300);
WIRE 17 -1 (-3250 2200)(-3250 2250);
WIRE 17 -1 (-3250 2150)(-3250 2200);
WIRE 17 -1 (-3250 2050)(-3250 2000);
WIRE 17 -1 (-3250 2050)(-3250 2075);
WIRE 17 -1 (-3250 1950)(-3250 2000);
WIRE 17 -1 (-3250 1950)(-3250 1900);
WIRE 17 -1 (-3250 2075)(-2750 2075);
FORCEPROP 2 LAST SIG_NAME M_A_CPU1_SB_CB<7:0>
J 2
(-2750 2085);
DISPLAY 0.489362 (-2750 2085);
WIRE 17 -1 (-3250 1850)(-3250 1900);
WIRE 17 -1 (-3250 1800)(-3250 1850);
WIRE 17 -1 (-3250 1750)(-3250 1800);
WIRE 17 -1 (-3250 1700)(-3250 1750);
WIRE 17 -1 (-5775 5400)(-5775 5300);
WIRE 17 -1 (-5775 5400)(-5775 5500);
WIRE 17 -1 (-5775 5300)(-5775 5200);
WIRE 17 -1 (-5775 5500)(-5775 5600);
WIRE 17 -1 (-5775 5600)(-5775 5700);
WIRE 17 -1 (-5775 5800)(-5775 5700);
WIRE 17 -1 (-5775 5900)(-5775 5800);
WIRE 17 -1 (-5775 6000)(-5775 5900);
WIRE 17 -1 (-5775 6100)(-5775 6000);
WIRE 17 -1 (-5775 6100)(-6575 6100);
FORCEPROP 2 LAST SIG_NAME M_A_CPU1_SA_DQS_DP<9:0>
J 2
(-6010 6110);
DISPLAY 0.489362 (-6010 6110);
WIRE 17 -1 (-5975 6050)(-5975 5950);
FORCEPROP 2 LAST SIG_NAME M_A_CPU1_SA_DQS_DN<9:0>
J 2
(-6010 6060);
DISPLAY 0.489362 (-6010 6060);
WIRE 17 -1 (-5975 5850)(-5975 5750);
WIRE 17 -1 (-5975 5950)(-5975 5850);
WIRE 17 -1 (-5975 5750)(-5975 5650);
WIRE 17 -1 (-5975 5550)(-5975 5650);
WIRE 17 -1 (-5975 5450)(-5975 5550);
WIRE 17 -1 (-5975 5350)(-5975 5450);
WIRE 17 -1 (-5975 5350)(-5975 5250);
WIRE 17 -1 (-5975 5250)(-5975 5150);
WIRE 17 -1 (-5975 4500)(-5975 4600);
WIRE 17 -1 (-5975 4400)(-5975 4500);
WIRE 17 -1 (-5975 4700)(-5975 4600);
WIRE 17 -1 (-5975 4800)(-5975 4700);
WIRE 17 -1 (-5975 4300)(-5975 4400);
WIRE 17 -1 (-5975 4300)(-5975 4200);
WIRE 17 -1 (-5975 4900)(-5975 4800);
WIRE 17 -1 (-5975 5000)(-5975 4900);
FORCEPROP 2 LAST SIG_NAME M_A_CPU1_SB_DQS_DN<9:0>
J 2
(-6010 5010);
DISPLAY 0.489362 (-6010 5010);
WIRE 17 -1 (-5775 4950)(-5775 4850);
WIRE 17 -1 (-5775 5050)(-5775 4950);
WIRE 17 -1 (-5775 4850)(-5775 4750);
WIRE 17 -1 (-5775 4750)(-5775 4650);
WIRE 17 -1 (-5775 5050)(-6575 5050);
FORCEPROP 2 LAST SIG_NAME M_A_CPU1_SB_DQS_DP<9:0>
J 2
(-6010 5060);
DISPLAY 0.489362 (-6010 5060);
WIRE 17 -1 (-5975 4200)(-5975 4100);
WIRE 17 -1 (-5775 4550)(-5775 4650);
WIRE 17 -1 (-5775 4450)(-5775 4550);
WIRE 17 -1 (-5775 4350)(-5775 4450);
WIRE 17 -1 (-5775 4350)(-5775 4250);
WIRE 17 -1 (-5775 4250)(-5775 4150);
WIRE 17 -1 (-5975 3900)(-5975 3950);
WIRE 17 -1 (-5975 3850)(-5975 3900);
WIRE 17 -1 (-5975 3950)(-6475 3950);
FORCEPROP 2 LAST SIG_NAME M_A_CPU1_SA_CA<6:0>
J 0
(-6475 3960);
DISPLAY 0.489362 (-6475 3960);
WIRE 17 -1 (-5975 3500)(-5975 3550);
WIRE 17 -1 (-5975 3450)(-5975 3500);
WIRE 17 -1 (-5975 3550)(-6475 3550);
FORCEPROP 2 LAST SIG_NAME M_A_CPU1_SB_CA<6:0>
J 0
(-6475 3560);
DISPLAY 0.489362 (-6475 3560);
WIRE 17 -1 (-5975 3800)(-5975 3850);
WIRE 17 -1 (-5975 3400)(-5975 3450);
WIRE 17 -1 (-5975 3750)(-5975 3800);
WIRE 17 -1 (-5975 3700)(-5975 3750);
WIRE 17 -1 (-5975 3650)(-5975 3700);
WIRE 17 -1 (-5975 3350)(-5975 3400);
WIRE 17 -1 (-5975 3300)(-5975 3350);
WIRE 17 -1 (-5975 3250)(-5975 3300);
WIRE 17 -1 (-5975 6050)(-6575 6050);
WIRE 17 -1 (-5975 5000)(-6575 5000);
WIRE 16 -1 (-7425 2225)(-6700 2225);
FORCEPROP 2 LAST SIG_NAME M_A_CPU1_ALERT_N
J 0
(-7385 2235);
DISPLAY 0.489362 (-7385 2235);
WIRE 16 -1 (-6475 1225)(-5375 1225);
FORCEPROP 2 LAST SIG_NAME TP_M_A_CPU1_SA_TEST40
J 0
(-6460 1235);
DISPLAY 0.489362 (-6460 1235);
FORCEPROP 2 LASTPROP $XRERR UNIQUE?
J 0
(-6715 1225);
DISPLAY 0.638298 (-6715 1225);
PAINT MONO (-6715 1225);
DISPLAY INVISIBLE (-6715 1225);
WIRE 16 -1 (-6475 1275)(-5375 1275);
FORCEPROP 2 LAST SIG_NAME TP_M_A_CPU1_SA_TEST39A
J 0
(-6460 1285);
DISPLAY 0.489362 (-6460 1285);
FORCEPROP 2 LASTPROP $XRERR UNIQUE?
J 0
(-6715 1275);
DISPLAY 0.638298 (-6715 1275);
PAINT MONO (-6715 1275);
DISPLAY INVISIBLE (-6715 1275);
WIRE 16 -1 (-6500 2225)(-5375 2225);
FORCEPROP 2 LAST SIG_NAME M_A_CPU1_ALERT_R_N
J 0
(-6210 2235);
DISPLAY 0.489362 (-6210 2235);
FORCEPROP 2 LASTPROP $XRERR UNIQUE?
J 0
(-6450 2235);
DISPLAY 0.638298 (-6450 2235);
PAINT MONO (-6450 2235);
DISPLAY INVISIBLE (-6450 2235);
WIRE 16 -1 (-6475 3075)(-5375 3075);
FORCEPROP 2 LAST SIG_NAME M_A_CPU1_CLK_DP<0>
J 0
(-6475 3085);
DISPLAY 0.489362 (-6475 3085);
WIRE 16 -1 (-6475 3025)(-5375 3025);
FORCEPROP 2 LAST SIG_NAME M_A_CPU1_CLK_DN<0>
J 0
(-6475 3035);
DISPLAY 0.489362 (-6475 3035);
WIRE 16 -1 (-6475 2925)(-5375 2925);
FORCEPROP 2 LAST SIG_NAME M_A_CPU1_SA_CS_N<0>
J 0
(-6475 2935);
DISPLAY 0.489362 (-6475 2935);
WIRE 16 -1 (-6475 2875)(-5375 2875);
FORCEPROP 2 LAST SIG_NAME M_A_CPU1_SA_CS_N<1>
J 0
(-6475 2885);
DISPLAY 0.489362 (-6475 2885);
WIRE 16 -1 (-6475 2775)(-5375 2775);
FORCEPROP 2 LAST SIG_NAME M_A_CPU1_SA_RSP<0>
J 0
(-6475 2785);
DISPLAY 0.489362 (-6475 2785);
WIRE 16 -1 (-6475 2675)(-5375 2675);
FORCEPROP 2 LAST SIG_NAME M_A_CPU1_SA_PAR
J 0
(-6475 2685);
DISPLAY 0.489362 (-6475 2685);
WIRE 16 -1 (-6475 2575)(-5375 2575);
FORCEPROP 2 LAST SIG_NAME M_A_CPU1_SB_CS_N<0>
J 0
(-6475 2585);
DISPLAY 0.489362 (-6475 2585);
WIRE 16 -1 (-6475 2525)(-5375 2525);
FORCEPROP 2 LAST SIG_NAME M_A_CPU1_SB_CS_N<1>
J 0
(-6475 2535);
DISPLAY 0.489362 (-6475 2535);
WIRE 16 -1 (-6475 2425)(-5375 2425);
FORCEPROP 2 LAST SIG_NAME M_A_CPU1_SB_RSP<0>
J 0
(-6475 2435);
DISPLAY 0.489362 (-6475 2435);
WIRE 16 -1 (-6475 2325)(-5375 2325);
FORCEPROP 2 LAST SIG_NAME M_A_CPU1_SB_PAR
J 0
(-6475 2335);
DISPLAY 0.489362 (-6475 2335);
WIRE 16 -1 (-6475 2125)(-5375 2125);
FORCEPROP 2 LAST SIG_NAME M_A_CPU1_RESET_N
J 0
(-6475 2135);
DISPLAY 0.489362 (-6475 2135);
WIRE 16 -1 (-5875 3225)(-5375 3225);
WIRE 16 -1 (-5875 3625)(-5375 3625);
WIRE 16 -1 (-5875 3275)(-5375 3275);
WIRE 16 -1 (-5875 3675)(-5375 3675);
WIRE 16 -1 (-5875 3325)(-5375 3325);
WIRE 16 -1 (-5875 3725)(-5375 3725);
WIRE 16 -1 (-5875 3375)(-5375 3375);
WIRE 16 -1 (-5875 3775)(-5375 3775);
WIRE 16 -1 (-5875 3425)(-5375 3425);
WIRE 16 -1 (-5875 3825)(-5375 3825);
WIRE 16 -1 (-5875 3475)(-5375 3475);
WIRE 16 -1 (-5875 3875)(-5375 3875);
WIRE 16 -1 (-5875 3525)(-5375 3525);
WIRE 16 -1 (-5875 3925)(-5375 3925);
WIRE 16 -1 (-5875 4075)(-5375 4075);
WIRE 16 -1 (-5675 4125)(-5375 4125);
WIRE 16 -1 (-5675 5025)(-5375 5025);
WIRE 16 -1 (-5875 4575)(-5375 4575);
WIRE 16 -1 (-5875 4675)(-5375 4675);
WIRE 16 -1 (-5875 4775)(-5375 4775);
WIRE 16 -1 (-5875 4875)(-5375 4875);
WIRE 16 -1 (-5875 4975)(-5375 4975);
WIRE 16 -1 (-5675 4225)(-5375 4225);
WIRE 16 -1 (-5675 4325)(-5375 4325);
WIRE 16 -1 (-5675 4425)(-5375 4425);
WIRE 16 -1 (-5675 4525)(-5375 4525);
WIRE 16 -1 (-5675 4625)(-5375 4625);
WIRE 16 -1 (-5875 4175)(-5375 4175);
WIRE 16 -1 (-5675 4725)(-5375 4725);
WIRE 16 -1 (-5875 4275)(-5375 4275);
WIRE 16 -1 (-5675 4825)(-5375 4825);
WIRE 16 -1 (-5875 4375)(-5375 4375);
WIRE 16 -1 (-5675 4925)(-5375 4925);
WIRE 16 -1 (-5875 4475)(-5375 4475);
WIRE 16 -1 (-5675 5475)(-5375 5475);
WIRE 16 -1 (-5675 5575)(-5375 5575);
WIRE 16 -1 (-5875 5125)(-5375 5125);
WIRE 16 -1 (-5675 5675)(-5375 5675);
WIRE 16 -1 (-5875 5225)(-5375 5225);
WIRE 16 -1 (-5675 5775)(-5375 5775);
WIRE 16 -1 (-5875 5325)(-5375 5325);
WIRE 16 -1 (-5675 5875)(-5375 5875);
WIRE 16 -1 (-5875 5425)(-5375 5425);
WIRE 16 -1 (-5675 5975)(-5375 5975);
WIRE 16 -1 (-5875 5525)(-5375 5525);
WIRE 16 -1 (-5675 6075)(-5375 6075);
WIRE 16 -1 (-5875 5625)(-5375 5625);
WIRE 16 -1 (-5875 5725)(-5375 5725);
WIRE 16 -1 (-5875 5825)(-5375 5825);
WIRE 16 -1 (-5875 5925)(-5375 5925);
WIRE 16 -1 (-5875 6025)(-5375 6025);
WIRE 16 -1 (-5675 5175)(-5375 5175);
WIRE 16 -1 (-5675 5275)(-5375 5275);
WIRE 16 -1 (-5675 5375)(-5375 5375);
WIRE 16 -1 (-3775 1675)(-3350 1675);
WIRE 16 -1 (-3775 1725)(-3350 1725);
WIRE 16 -1 (-3775 1775)(-3350 1775);
WIRE 16 -1 (-3775 1825)(-3350 1825);
WIRE 16 -1 (-3775 1875)(-3350 1875);
WIRE 16 -1 (-3775 1925)(-3350 1925);
WIRE 16 -1 (-3775 1975)(-3350 1975);
WIRE 16 -1 (-3775 2025)(-3350 2025);
WIRE 16 -1 (-3775 2725)(-3350 2725);
WIRE 16 -1 (-3775 2775)(-3350 2775);
WIRE 16 -1 (-3775 2825)(-3350 2825);
WIRE 16 -1 (-3775 2875)(-3350 2875);
WIRE 16 -1 (-3775 2925)(-3350 2925);
WIRE 16 -1 (-3775 3025)(-3350 3025);
WIRE 16 -1 (-3775 2125)(-3350 2125);
WIRE 16 -1 (-3775 2175)(-3350 2175);
WIRE 16 -1 (-3775 2575)(-3350 2575);
WIRE 16 -1 (-3775 2225)(-3350 2225);
WIRE 16 -1 (-3775 2625)(-3350 2625);
WIRE 16 -1 (-3775 2275)(-3350 2275);
WIRE 16 -1 (-3775 2325)(-3350 2325);
WIRE 16 -1 (-3775 2375)(-3350 2375);
WIRE 16 -1 (-3775 2425)(-3350 2425);
WIRE 16 -1 (-3775 2475)(-3350 2475);
WIRE 16 -1 (-3775 2675)(-3350 2675);
WIRE 16 -1 (-3775 3325)(-3350 3325);
WIRE 16 -1 (-3775 3375)(-3350 3375);
WIRE 16 -1 (-3775 3475)(-3350 3475);
WIRE 16 -1 (-3775 3525)(-3350 3525);
WIRE 16 -1 (-3775 3575)(-3350 3575);
WIRE 16 -1 (-3775 3625)(-3350 3625);
WIRE 16 -1 (-3775 3675)(-3350 3675);
WIRE 16 -1 (-3775 3075)(-3350 3075);
WIRE 16 -1 (-3775 3725)(-3350 3725);
WIRE 16 -1 (-3775 3125)(-3350 3125);
WIRE 16 -1 (-3775 3175)(-3350 3175);
WIRE 16 -1 (-3775 3775)(-3350 3775);
WIRE 16 -1 (-3775 3825)(-3350 3825);
WIRE 16 -1 (-3775 3925)(-3350 3925);
WIRE 16 -1 (-3775 3975)(-3350 3975);
WIRE 16 -1 (-3775 4025)(-3350 4025);
WIRE 16 -1 (-3775 4075)(-3350 4075);
WIRE 16 -1 (-3775 3225)(-3350 3225);
WIRE 16 -1 (-3775 3275)(-3350 3275);
WIRE 16 -1 (-3775 4175)(-3350 4175);
WIRE 16 -1 (-3775 4225)(-3350 4225);
WIRE 16 -1 (-3775 4275)(-3350 4275);
WIRE 16 -1 (-3775 5025)(-3350 5025);
WIRE 16 -1 (-3775 5075)(-3350 5075);
WIRE 16 -1 (-3775 4475)(-3350 4475);
WIRE 16 -1 (-3775 4525)(-3350 4525);
WIRE 16 -1 (-3775 4575)(-3350 4575);
WIRE 16 -1 (-3775 4625)(-3350 4625);
WIRE 16 -1 (-3775 4675)(-3350 4675);
WIRE 16 -1 (-3775 4725)(-3350 4725);
WIRE 16 -1 (-3775 4825)(-3350 4825);
WIRE 16 -1 (-3775 4875)(-3350 4875);
WIRE 16 -1 (-3775 4925)(-3350 4925);
WIRE 16 -1 (-3775 4975)(-3350 4975);
WIRE 16 -1 (-3775 4375)(-3350 4375);
WIRE 16 -1 (-3775 4425)(-3350 4425);
WIRE 16 -1 (-3775 4125)(-3350 4125);
WIRE 16 -1 (-3775 5925)(-3350 5925);
WIRE 16 -1 (-3775 5975)(-3350 5975);
WIRE 16 -1 (-3775 6025)(-3350 6025);
WIRE 16 -1 (-3775 6075)(-3350 6075);
WIRE 16 -1 (-3775 5125)(-3350 5125);
WIRE 16 -1 (-3775 5175)(-3350 5175);
WIRE 16 -1 (-3775 5275)(-3350 5275);
WIRE 16 -1 (-3775 5325)(-3350 5325);
WIRE 16 -1 (-3775 5375)(-3350 5375);
WIRE 16 -1 (-3775 5575)(-3350 5575);
WIRE 16 -1 (-3775 5425)(-3350 5425);
WIRE 16 -1 (-3775 5625)(-3350 5625);
WIRE 16 -1 (-3775 5475)(-3350 5475);
WIRE 16 -1 (-3775 5725)(-3350 5725);
WIRE 16 -1 (-3775 5525)(-3350 5525);
WIRE 16 -1 (-3775 5775)(-3350 5775);
WIRE 16 -1 (-3775 5825)(-3350 5825);
WIRE 16 -1 (-3775 5875)(-3350 5875);
QUIT
